G04 ================== begin FILE IDENTIFICATION RECORD ==================*
G04 Layout Name:  13130-1b.brd*
G04 Film Name:    L9GND*
G04 File Format:  Gerber RS274X*
G04 File Origin:  Cadence Allegro 16.5-S037*
G04 Origin Date:  Thu Nov 13 17:27:13 2014*
G04 *
G04 Layer:  VIA CLASS/L9GND*
G04 Layer:  PIN/L9GND*
G04 Layer:  ETCH/L9GND*
G04 Layer:  DRAWING FORMAT/LAYER_PCB_STORY*
G04 Layer:  DRAWING FORMAT/LAYER_L9GND*
G04 *
G04 Offset:    (0.00 0.00)*
G04 Mirror:    No*
G04 Mode:      Negative*
G04 Rotation:  0*
G04 FullContactRelief:  No*
G04 UndefLineWidth:     6.00*
G04 ================== end FILE IDENTIFICATION RECORD ====================*
%FSLAX35Y35*MOIN*%
%IR0*IPPOS*OFA0.00000B0.00000*MIA0B0*SFA1.00000B1.00000*%
%ADD15C,.03*%
%ADD20C,.032*%
%ADD18C,.072*%
%ADD13C,.036*%
%ADD24C,.028*%
%ADD22C,.091*%
%ADD17C,.093*%
%ADD19C,.068*%
%AMMACRO23*
4,1,15,.00398,.00044,
.003999,.000208,
.004004,-.000025,
.003996,-.000258,
.00398,-.00044,
.00483,-.00129,
.004897,-.001007,
.004947,-.000721,
.004981,-.000432,
.004997,-.000141,
.004997,.000149,
.00498,.00044,
.004946,.000729,
.004895,.001015,
.00483,.00129,
.00398,.00044,
45.*
4,1,15,.00044,-.00398,
.000208,-.003999,
-.000025,-.004004,
-.000258,-.003996,
-.00044,-.00398,
-.00129,-.00483,
-.001007,-.004897,
-.000721,-.004947,
-.000432,-.004981,
-.000141,-.004997,
.000149,-.004997,
.00044,-.00498,
.000729,-.004946,
.001015,-.004895,
.00129,-.00483,
.00044,-.00398,
45.*
4,1,15,-.00398,-.00044,
-.003999,-.000208,
-.004004,.000025,
-.003996,.000258,
-.00398,.00044,
-.00483,.00129,
-.004897,.001007,
-.004947,.000721,
-.004981,.000432,
-.004997,.000141,
-.004997,-.000149,
-.00498,-.00044,
-.004946,-.000729,
-.004895,-.001015,
-.00483,-.00129,
-.00398,-.00044,
45.*
4,1,15,-.00044,.00398,
-.000208,.003999,
.000025,.004004,
.000258,.003996,
.00044,.00398,
.00129,.00483,
.001007,.004897,
.000721,.004947,
.000432,.004981,
.000141,.004997,
-.000149,.004997,
-.00044,.00498,
-.000729,.004946,
-.001015,.004895,
-.00129,.00483,
-.00044,.00398,
45.*
%
%ADD23MACRO23*%
%AMMACRO14*
4,1,15,.00398,.00044,
.003999,.000208,
.004004,-.000025,
.003996,-.000258,
.00398,-.00044,
.00483,-.00129,
.004897,-.001007,
.004947,-.000721,
.004981,-.000432,
.004997,-.000141,
.004997,.000149,
.00498,.00044,
.004946,.000729,
.004895,.001015,
.00483,.00129,
.00398,.00044,
90.*
4,1,15,.00044,-.00398,
.000208,-.003999,
-.000025,-.004004,
-.000258,-.003996,
-.00044,-.00398,
-.00129,-.00483,
-.001007,-.004897,
-.000721,-.004947,
-.000432,-.004981,
-.000141,-.004997,
.000149,-.004997,
.00044,-.00498,
.000729,-.004946,
.001015,-.004895,
.00129,-.00483,
.00044,-.00398,
90.*
4,1,15,-.00398,-.00044,
-.003999,-.000208,
-.004004,.000025,
-.003996,.000258,
-.00398,.00044,
-.00483,.00129,
-.004897,.001007,
-.004947,.000721,
-.004981,.000432,
-.004997,.000141,
-.004997,-.000149,
-.00498,-.00044,
-.004946,-.000729,
-.004895,-.001015,
-.00483,-.00129,
-.00398,-.00044,
90.*
4,1,15,-.00044,.00398,
-.000208,.003999,
.000025,.004004,
.000258,.003996,
.00044,.00398,
.00129,.00483,
.001007,.004897,
.000721,.004947,
.000432,.004981,
.000141,.004997,
-.000149,.004997,
-.00044,.00498,
-.000729,.004946,
-.001015,.004895,
-.00129,.00483,
-.00044,.00398,
90.*
%
%ADD14MACRO14*%
%AMMACRO12*
4,1,15,.00398,.00044,
.003999,.000208,
.004004,-.000025,
.003996,-.000258,
.00398,-.00044,
.00483,-.00129,
.004897,-.001007,
.004947,-.000721,
.004981,-.000432,
.004997,-.000141,
.004997,.000149,
.00498,.00044,
.004946,.000729,
.004895,.001015,
.00483,.00129,
.00398,.00044,
0.0*
4,1,15,.00044,-.00398,
.000208,-.003999,
-.000025,-.004004,
-.000258,-.003996,
-.00044,-.00398,
-.00129,-.00483,
-.001007,-.004897,
-.000721,-.004947,
-.000432,-.004981,
-.000141,-.004997,
.000149,-.004997,
.00044,-.00498,
.000729,-.004946,
.001015,-.004895,
.00129,-.00483,
.00044,-.00398,
0.0*
4,1,15,-.00398,-.00044,
-.003999,-.000208,
-.004004,.000025,
-.003996,.000258,
-.00398,.00044,
-.00483,.00129,
-.004897,.001007,
-.004947,.000721,
-.004981,.000432,
-.004997,.000141,
-.004997,-.000149,
-.00498,-.00044,
-.004946,-.000729,
-.004895,-.001015,
-.00483,-.00129,
-.00398,-.00044,
0.0*
4,1,15,-.00044,.00398,
-.000208,.003999,
.000025,.004004,
.000258,.003996,
.00044,.00398,
.00129,.00483,
.001007,.004897,
.000721,.004947,
.000432,.004981,
.000141,.004997,
-.000149,.004997,
-.00044,.00498,
-.000729,.004946,
-.001015,.004895,
-.00129,.00483,
-.00044,.00398,
0.0*
%
%ADD12MACRO12*%
%AMMACRO31*
4,1,14,.02782,.01368,
.029773,.008641,
.030821,.00334,
.030933,-.002063,
.030105,-.007403,
.028362,-.012518,
.02782,-.01368,
.03153,-.01738,
.034069,-.011641,
.035573,-.005548,
.035996,.000713,
.035325,.006953,
.033581,.012982,
.03153,.01738,
.02782,.01368,
270.*
4,1,14,.01368,-.02782,
.008641,-.029773,
.00334,-.030821,
-.002063,-.030933,
-.007403,-.030105,
-.012518,-.028362,
-.01368,-.02782,
-.01738,-.03153,
-.011641,-.034069,
-.005548,-.035573,
.000713,-.035996,
.006953,-.035325,
.012982,-.033581,
.01738,-.03153,
.01368,-.02782,
270.*
4,1,14,-.02782,-.01368,
-.029773,-.008641,
-.030821,-.00334,
-.030933,.002063,
-.030105,.007403,
-.028362,.012518,
-.02782,.01368,
-.03153,.01738,
-.034069,.011641,
-.035573,.005548,
-.035996,-.000713,
-.035325,-.006953,
-.033581,-.012982,
-.03153,-.01738,
-.02782,-.01368,
270.*
4,1,14,-.01368,.02782,
-.008641,.029773,
-.00334,.030821,
.002063,.030933,
.007403,.030105,
.012518,.028362,
.01368,.02782,
.01738,.03153,
.011641,.034069,
.005548,.035573,
-.000713,.035996,
-.006953,.035325,
-.012982,.033581,
-.01738,.03153,
-.01368,.02782,
270.*
%
%ADD31MACRO31*%
%ADD29O,.217X.154*%
%ADD11C,.114*%
%ADD16C,.154*%
%ADD21C,.147*%
%ADD10C,.168*%
%AMMACRO30*
4,1,15,.00398,.00044,
.003999,.000208,
.004004,-.000025,
.003996,-.000258,
.00398,-.00044,
.00483,-.00129,
.004897,-.001007,
.004947,-.000721,
.004981,-.000432,
.004997,-.000141,
.004997,.000149,
.00498,.00044,
.004946,.000729,
.004895,.001015,
.00483,.00129,
.00398,.00044,
225.*
4,1,15,.00044,-.00398,
.000208,-.003999,
-.000025,-.004004,
-.000258,-.003996,
-.00044,-.00398,
-.00129,-.00483,
-.001007,-.004897,
-.000721,-.004947,
-.000432,-.004981,
-.000141,-.004997,
.000149,-.004997,
.00044,-.00498,
.000729,-.004946,
.001015,-.004895,
.00129,-.00483,
.00044,-.00398,
225.*
4,1,15,-.00398,-.00044,
-.003999,-.000208,
-.004004,.000025,
-.003996,.000258,
-.00398,.00044,
-.00483,.00129,
-.004897,.001007,
-.004947,.000721,
-.004981,.000432,
-.004997,.000141,
-.004997,-.000149,
-.00498,-.00044,
-.004946,-.000729,
-.004895,-.001015,
-.00483,-.00129,
-.00398,-.00044,
225.*
4,1,15,-.00044,.00398,
-.000208,.003999,
.000025,.004004,
.000258,.003996,
.00044,.00398,
.00129,.00483,
.001007,.004897,
.000721,.004947,
.000432,.004981,
.000141,.004997,
-.000149,.004997,
-.00044,.00498,
-.000729,.004946,
-.001015,.004895,
-.00129,.00483,
-.00044,.00398,
225.*
%
%ADD30MACRO30*%
%AMMACRO28*
4,1,15,.00398,.00044,
.003999,.000208,
.004004,-.000025,
.003996,-.000258,
.00398,-.00044,
.00483,-.00129,
.004897,-.001007,
.004947,-.000721,
.004981,-.000432,
.004997,-.000141,
.004997,.000149,
.00498,.00044,
.004946,.000729,
.004895,.001015,
.00483,.00129,
.00398,.00044,
315.*
4,1,15,.00044,-.00398,
.000208,-.003999,
-.000025,-.004004,
-.000258,-.003996,
-.00044,-.00398,
-.00129,-.00483,
-.001007,-.004897,
-.000721,-.004947,
-.000432,-.004981,
-.000141,-.004997,
.000149,-.004997,
.00044,-.00498,
.000729,-.004946,
.001015,-.004895,
.00129,-.00483,
.00044,-.00398,
315.*
4,1,15,-.00398,-.00044,
-.003999,-.000208,
-.004004,.000025,
-.003996,.000258,
-.00398,.00044,
-.00483,.00129,
-.004897,.001007,
-.004947,.000721,
-.004981,.000432,
-.004997,.000141,
-.004997,-.000149,
-.00498,-.00044,
-.004946,-.000729,
-.004895,-.001015,
-.00483,-.00129,
-.00398,-.00044,
315.*
4,1,15,-.00044,.00398,
-.000208,.003999,
.000025,.004004,
.000258,.003996,
.00044,.00398,
.00129,.00483,
.001007,.004897,
.000721,.004947,
.000432,.004981,
.000141,.004997,
-.000149,.004997,
-.00044,.00498,
-.000729,.004946,
-.001015,.004895,
-.00129,.00483,
-.00044,.00398,
315.*
%
%ADD28MACRO28*%
%AMMACRO27*
4,1,15,.00398,.00044,
.003999,.000208,
.004004,-.000025,
.003996,-.000258,
.00398,-.00044,
.00483,-.00129,
.004897,-.001007,
.004947,-.000721,
.004981,-.000432,
.004997,-.000141,
.004997,.000149,
.00498,.00044,
.004946,.000729,
.004895,.001015,
.00483,.00129,
.00398,.00044,
180.*
4,1,15,.00044,-.00398,
.000208,-.003999,
-.000025,-.004004,
-.000258,-.003996,
-.00044,-.00398,
-.00129,-.00483,
-.001007,-.004897,
-.000721,-.004947,
-.000432,-.004981,
-.000141,-.004997,
.000149,-.004997,
.00044,-.00498,
.000729,-.004946,
.001015,-.004895,
.00129,-.00483,
.00044,-.00398,
180.*
4,1,15,-.00398,-.00044,
-.003999,-.000208,
-.004004,.000025,
-.003996,.000258,
-.00398,.00044,
-.00483,.00129,
-.004897,.001007,
-.004947,.000721,
-.004981,.000432,
-.004997,.000141,
-.004997,-.000149,
-.00498,-.00044,
-.004946,-.000729,
-.004895,-.001015,
-.00483,-.00129,
-.00398,-.00044,
180.*
4,1,15,-.00044,.00398,
-.000208,.003999,
.000025,.004004,
.000258,.003996,
.00044,.00398,
.00129,.00483,
.001007,.004897,
.000721,.004947,
.000432,.004981,
.000141,.004997,
-.000149,.004997,
-.00044,.00498,
-.000729,.004946,
-.001015,.004895,
-.00129,.00483,
-.00044,.00398,
180.*
%
%ADD27MACRO27*%
%AMMACRO26*
4,1,15,.00398,.00044,
.003999,.000208,
.004004,-.000025,
.003996,-.000258,
.00398,-.00044,
.00483,-.00129,
.004897,-.001007,
.004947,-.000721,
.004981,-.000432,
.004997,-.000141,
.004997,.000149,
.00498,.00044,
.004946,.000729,
.004895,.001015,
.00483,.00129,
.00398,.00044,
270.*
4,1,15,.00044,-.00398,
.000208,-.003999,
-.000025,-.004004,
-.000258,-.003996,
-.00044,-.00398,
-.00129,-.00483,
-.001007,-.004897,
-.000721,-.004947,
-.000432,-.004981,
-.000141,-.004997,
.000149,-.004997,
.00044,-.00498,
.000729,-.004946,
.001015,-.004895,
.00129,-.00483,
.00044,-.00398,
270.*
4,1,15,-.00398,-.00044,
-.003999,-.000208,
-.004004,.000025,
-.003996,.000258,
-.00398,.00044,
-.00483,.00129,
-.004897,.001007,
-.004947,.000721,
-.004981,.000432,
-.004997,.000141,
-.004997,-.000149,
-.00498,-.00044,
-.004946,-.000729,
-.004895,-.001015,
-.00483,-.00129,
-.00398,-.00044,
270.*
4,1,15,-.00044,.00398,
-.000208,.003999,
.000025,.004004,
.000258,.003996,
.00044,.00398,
.00129,.00483,
.001007,.004897,
.000721,.004947,
.000432,.004981,
.000141,.004997,
-.000149,.004997,
-.00044,.00498,
-.000729,.004946,
-.001015,.004895,
-.00129,.00483,
-.00044,.00398,
270.*
%
%ADD26MACRO26*%
%AMMACRO25*
4,1,15,.00398,.00044,
.003999,.000208,
.004004,-.000025,
.003996,-.000258,
.00398,-.00044,
.00483,-.00129,
.004897,-.001007,
.004947,-.000721,
.004981,-.000432,
.004997,-.000141,
.004997,.000149,
.00498,.00044,
.004946,.000729,
.004895,.001015,
.00483,.00129,
.00398,.00044,
135.*
4,1,15,.00044,-.00398,
.000208,-.003999,
-.000025,-.004004,
-.000258,-.003996,
-.00044,-.00398,
-.00129,-.00483,
-.001007,-.004897,
-.000721,-.004947,
-.000432,-.004981,
-.000141,-.004997,
.000149,-.004997,
.00044,-.00498,
.000729,-.004946,
.001015,-.004895,
.00129,-.00483,
.00044,-.00398,
135.*
4,1,15,-.00398,-.00044,
-.003999,-.000208,
-.004004,.000025,
-.003996,.000258,
-.00398,.00044,
-.00483,.00129,
-.004897,.001007,
-.004947,.000721,
-.004981,.000432,
-.004997,.000141,
-.004997,-.000149,
-.00498,-.00044,
-.004946,-.000729,
-.004895,-.001015,
-.00483,-.00129,
-.00398,-.00044,
135.*
4,1,15,-.00044,.00398,
-.000208,.003999,
.000025,.004004,
.000258,.003996,
.00044,.00398,
.00129,.00483,
.001007,.004897,
.000721,.004947,
.000432,.004981,
.000141,.004997,
-.000149,.004997,
-.00044,.00498,
-.000729,.004946,
-.001015,.004895,
-.00129,.00483,
-.00044,.00398,
135.*
%
%ADD25MACRO25*%
%ADD32C,.02*%
%ADD33C,.006*%
%ADD41C,.03004*%
%ADD39C,.06404*%
%ADD38C,.06804*%
%ADD40C,.08704*%
%ADD37C,.08904*%
%ADD34O,.21302X.15002*%
%ADD35C,.11004*%
%ADD36C,.15004*%
G75*
%LPD*%
G75*
G36*
G01X-6000Y-6000D02*
X832773D01*
Y296551D01*
X-6000D01*
Y-6000D01*
G37*
%LPC*%
G75*
G36*
G01X3937Y60878D02*
G02X3004Y61811I0J933D01*
G01Y286614D01*
G02X3937Y287547I933J0D01*
G01X193177D01*
G02X193514Y286932I0J-400D01*
G03X206880I6683J-4255D01*
G02X207217Y287547I337J215D01*
G01X291579D01*
G02X291917Y286933I0J-400D01*
G03X305327I6705J-4256D01*
G02X305665Y287547I338J214D01*
G01X822835D01*
G02X823768Y286614I0J-933D01*
G01Y3937D01*
G02X822835Y3004I-933J0D01*
G01X417323D01*
G02X416390Y3937I0J933D01*
G01Y42126D01*
G03X409449Y49067I-6941J0D01*
G01X393701D01*
G03X386760Y42126I0J-6941D01*
G01Y20648D01*
X348673D01*
Y39961D01*
G03X335185I-6744J0D01*
G01Y20648D01*
X60878D01*
Y53937D01*
G03X53937Y60878I-6941J0D01*
G01X3937D01*
G37*
%LPD*%
G75*
G36*
G01X391270Y128621D02*
X395751Y133102D01*
X409749D01*
X412249Y130602D01*
X431975D01*
X432172Y130626D01*
X432204Y130602D01*
X432206D01*
X432208Y130600D01*
X432249D01*
X432392Y130457D01*
X433106Y129902D01*
X435951D01*
X437151Y131102D01*
X443249D01*
X451749Y122602D01*
X463540D01*
X463689Y122750D01*
X464311D01*
X468811Y118250D01*
X623811D01*
X681750Y60311D01*
Y44689D01*
X679250Y42189D01*
Y30689D01*
X672750Y24189D01*
Y17189D01*
X669750Y14189D01*
Y11189D01*
X666311Y7750D01*
X599689D01*
X569689Y37750D01*
X532689D01*
X516689Y53750D01*
X449189D01*
X426189Y76750D01*
X396797D01*
X396786Y76740D01*
X396488Y76750D01*
X396189D01*
X396179Y76760D01*
X396165D01*
X395961Y76978D01*
X395750Y77189D01*
Y77203D01*
X388240Y85214D01*
X388260Y85835D01*
X388398Y85965D01*
Y96251D01*
X382898Y101751D01*
Y126249D01*
X384251Y127602D01*
X388748D01*
G02X390996Y128613I1352J-2D01*
G03X391270Y128621I133J150D01*
G37*
G36*
G01X6090Y260713D02*
Y264483D01*
G02X9110I1510J0D01*
G01Y260712D01*
G02X6090Y260713I-1510J1D01*
G37*
G36*
G01X12080Y254751D02*
Y258521D01*
G02X15100I1510J0D01*
G01Y254750D01*
G02X12080Y254751I-1510J1D01*
G37*
G36*
G01X36390Y254000D02*
Y257500D01*
G02X39410I1510J0D01*
G01Y253999D01*
G02X36390Y254000I-1510J1D01*
G37*
G36*
G01X6090Y248902D02*
Y252673D01*
G02X9110Y252672I1510J-1D01*
G01Y248902D01*
G02X6090I-1510J0D01*
G37*
G36*
G01X36397Y246861D02*
X36381Y247035D01*
X36481Y250542D01*
X36489Y250550D01*
X36495Y250624D01*
G02X39503Y250639I1505J-123D01*
G01X39519Y250465D01*
X39419Y246957D01*
X39394Y246785D01*
G02X36397Y246861I-1494J216D01*
G37*
G36*
G01X398368Y244905D02*
X400768Y247314D01*
G02X402908Y245182I1070J-1066D01*
G01X400529Y242795D01*
X400528Y242794D01*
G02X398368Y244905I-1090J1045D01*
G37*
G36*
G01X12080Y242940D02*
Y246710D01*
G02X15100I1510J0D01*
G01Y242939D01*
G02X12080Y242940I-1510J1D01*
G37*
G36*
G01X36390Y240000D02*
Y243500D01*
G02X39410I1510J0D01*
G01Y239999D01*
G02X36390Y240000I-1510J1D01*
G37*
G36*
G01X390616Y239712D02*
X390725Y239846D01*
X393170Y242218D01*
X393181D01*
X393237Y242267D01*
G02X395280Y240044I991J-1139D01*
G01X395137Y239905D01*
X395143Y239898D01*
X392844Y237667D01*
X392707Y237562D01*
G02X390616Y239712I-919J1198D01*
G37*
G36*
G01X6090Y237091D02*
Y240861D01*
G02X9110I1510J0D01*
G01Y237090D01*
G02X6090Y237091I-1510J1D01*
G37*
G36*
G01X36397Y232861D02*
X36381Y233035D01*
X36481Y236542D01*
X36489Y236550D01*
X36495Y236624D01*
G02X39503Y236639I1505J-123D01*
G01X39519Y236465D01*
X39419Y232957D01*
X39394Y232785D01*
G02X36397Y232861I-1494J216D01*
G37*
G36*
G01X11580Y231129D02*
Y234900D01*
G02X14600Y234899I1510J-1D01*
G01Y231129D01*
G02X11580I-1510J0D01*
G37*
G36*
G01X36390Y226000D02*
Y229500D01*
G02X39410I1510J0D01*
G01Y225999D01*
G02X36390Y226000I-1510J1D01*
G37*
G36*
G01Y219000D02*
Y222500D01*
G02X39410I1510J0D01*
G01Y218999D01*
G02X36390Y219000I-1510J1D01*
G37*
G36*
G01X327485Y217426D02*
X325999Y219130D01*
G02X328049Y220918I1025J894D01*
G01X329534Y219215D01*
G02X327485Y217426I-1025J-895D01*
G37*
G36*
G01X359255Y215107D02*
X359109Y215175D01*
X357235Y216357D01*
Y216365D01*
X357154Y216425D01*
G02X358692Y218666I812J1091D01*
G01X358861Y218559D01*
X358866Y218567D01*
X360570Y217492D01*
X360694Y217389D01*
G02X359255Y215107I-867J-1048D01*
G37*
G36*
G01X335981Y215710D02*
X335947Y217939D01*
G02X338667Y217982I1360J22D01*
G01X338701Y215752D01*
G02X335981Y215710I-1360J-21D01*
G37*
G36*
G01X341882Y213663D02*
X341838Y215882D01*
G02X344558Y215937I1360J27D01*
G01X344602Y213717D01*
G02X341882Y213663I-1360J-27D01*
G37*
G36*
G01X330298Y212634D02*
X330256Y214834D01*
G02X332976Y214886I1360J26D01*
G01X333018Y212687D01*
G02X330298Y212634I-1360J-26D01*
G37*
G36*
G01X352240Y210578D02*
X352031Y212769D01*
G02X354739Y213027I1354J129D01*
G01X354948Y210837D01*
G02X352240Y210578I-1354J-129D01*
G37*
G36*
G01X346240Y210141D02*
X346224Y210306D01*
X346295Y212525D01*
X346321Y212689D01*
G02X349017Y212612I1343J-213D01*
G01X349033Y212447D01*
X348962Y210234D01*
X348954Y210226D01*
X348947Y210154D01*
G02X346240Y210141I-1354J123D01*
G37*
G36*
G01X357162Y209968D02*
X357131Y210131D01*
X357014Y212358D01*
X357026Y212523D01*
G02X359740Y212498I1356J-97D01*
G01X359750Y212299D01*
X359761D01*
X359866Y210293D01*
X359859Y210286D01*
X359858Y210204D01*
G02X357162Y209968I-1360J16D01*
G37*
G36*
G01X337607Y209430D02*
X337566Y211648D01*
G02X340286Y211699I1360J26D01*
G01X340327Y209480D01*
G02X337607Y209430I-1360J-25D01*
G37*
G36*
G01X50350Y187640D02*
Y191411D01*
G02X53370Y191410I1510J-1D01*
G01Y187640D01*
G02X50350I-1510J0D01*
G37*
G36*
G01X197931Y187525D02*
X197882Y190925D01*
G02X200902Y190969I1510J22D01*
G01X200951Y187570D01*
G02X197931Y187525I-1510J-23D01*
G37*
G36*
G01X59379Y182870D02*
X55719D01*
G02X55720Y185890I1J1510D01*
G01X59379D01*
G02Y182870I0J-1510D01*
G37*
G36*
G01X238393Y180697D02*
X238612Y184090D01*
G02X241626Y183896I1507J-97D01*
G01X241407Y180504D01*
G02X238393Y180697I-1507J97D01*
G37*
G36*
G01X170910Y172330D02*
X167139D01*
G02X167140Y175350I1J1510D01*
G01X170910D01*
G02Y172330I0J-1510D01*
G37*
G36*
G01X177125Y174410D02*
X180897Y174495D01*
G02X180965Y171475I34J-1510D01*
G01X177194Y171390D01*
G02X177125Y174410I-35J1510D01*
G37*
G36*
G01X193608Y150841D02*
X196115Y153119D01*
X196116Y153120D01*
G02X198155Y150892I1024J-1110D01*
G01X195638Y148605D01*
G02X193608Y150841I-1015J1118D01*
G37*
G36*
G01X233365Y139290D02*
Y143060D01*
G02X236385I1510J0D01*
G01Y139289D01*
G02X233365Y139290I-1510J1D01*
G37*
G36*
G01X210542Y137518D02*
X206785Y137530D01*
G02X206795Y140550I5J1510D01*
G01X210551Y140538D01*
G02X210542Y137518I-5J-1510D01*
G37*
G36*
G01X205380Y132690D02*
X201898D01*
G02X201899Y135710I1J1510D01*
G01X205380D01*
G02Y132690I0J-1510D01*
G37*
G36*
G01X149160Y115500D02*
Y118900D01*
G02X152180I1510J0D01*
G01Y115499D01*
G02X149160Y115500I-1510J1D01*
G37*
G36*
G01X207749Y113771D02*
Y117431D01*
G02X210769Y117430I1510J-1D01*
G01Y113771D01*
G02X207749I-1510J0D01*
G37*
G36*
G01X270690Y108345D02*
X270675Y111824D01*
G02X273695Y111838I1510J7D01*
G01X273710Y108360D01*
G02X270690Y108345I-1510J-7D01*
G37*
G36*
G01X197845Y78850D02*
X194074D01*
G02X194075Y81870I1J1510D01*
G01X197845D01*
G02Y78850I0J-1510D01*
G37*
G36*
G01X82885Y59469D02*
X79115D01*
G02Y62489I0J1510D01*
G01X82886D01*
G02X82885Y59469I-1J-1510D01*
G37*
G36*
G01X290200Y56390D02*
X286799D01*
G02X286800Y59410I1J1510D01*
G01X290200D01*
G02Y56390I0J-1510D01*
G37*
G36*
G01X271000Y55990D02*
X267999D01*
G02X268000Y59010I1J1510D01*
G01X271000D01*
G02Y55990I0J-1510D01*
G37*
G36*
G01X319200Y55890D02*
X315800D01*
G02Y58910I0J1510D01*
G01X319201D01*
G02X319200Y55890I-1J-1510D01*
G37*
G36*
G01X308200D02*
X304799D01*
G02X304800Y58910I1J1510D01*
G01X308200D01*
G02Y55890I0J-1510D01*
G37*
G36*
G01X135000D02*
X131600D01*
G02Y58910I0J1510D01*
G01X135001D01*
G02X135000Y55890I-1J-1510D01*
G37*
G36*
G01X119200D02*
X115800D01*
G02Y58910I0J1510D01*
G01X119201D01*
G02X119200Y55890I-1J-1510D01*
G37*
G36*
G01X327400Y53390D02*
X323999D01*
G02X324000Y56410I1J1510D01*
G01X327400D01*
G02Y53390I0J-1510D01*
G37*
G36*
G01X208700D02*
X205300D01*
G02Y56410I0J1510D01*
G01X208701D01*
G02X208700Y53390I-1J-1510D01*
G37*
G36*
G01X166463Y52890D02*
X163063D01*
G02Y55910I0J1510D01*
G01X166464D01*
G02X166463Y52890I-1J-1510D01*
G37*
G36*
G01X150715D02*
X147315D01*
G02Y55910I0J1510D01*
G01X150716D01*
G02X150715Y52890I-1J-1510D01*
G37*
G36*
G01X103450D02*
X100050D01*
G02Y55910I0J1510D01*
G01X103451D01*
G02X103450Y52890I-1J-1510D01*
G37*
G36*
G01X88700D02*
X85299D01*
G02X85300Y55910I1J1510D01*
G01X88700D01*
G02Y52890I0J-1510D01*
G37*
G36*
G01X174060Y48090D02*
X170290D01*
G02Y51110I0J1510D01*
G01X174061D01*
G02X174060Y48090I-1J-1510D01*
G37*
G36*
G01X159060Y47100D02*
X155289D01*
G02X155290Y50120I1J1510D01*
G01X159060D01*
G02Y47100I0J-1510D01*
G37*
G36*
G01X236211Y41547D02*
X232590D01*
G02X232591Y44567I1J1510D01*
G01X236211D01*
G02Y41547I0J-1510D01*
G37*
G36*
G01X331931Y39485D02*
X328302D01*
G02X328303Y42505I1J1510D01*
G01X331931D01*
G02Y39485I0J-1510D01*
G37*
G36*
G01X316254Y39180D02*
X312483D01*
G02X312484Y42200I1J1510D01*
G01X316254D01*
G02Y39180I0J-1510D01*
G37*
G36*
G01X300506Y38980D02*
X296735D01*
G02X296736Y42000I1J1510D01*
G01X300506D01*
G02Y38980I0J-1510D01*
G37*
G36*
G01X284758D02*
X280987D01*
G02X280988Y42000I1J1510D01*
G01X284758D01*
G02Y38980I0J-1510D01*
G37*
G36*
G01X268910D02*
X265140D01*
G02Y42000I0J1510D01*
G01X268911D01*
G02X268910Y38980I-1J-1510D01*
G37*
G36*
G01X198073Y38885D02*
X194444D01*
G02X194445Y41905I1J1510D01*
G01X198073D01*
G02Y38885I0J-1510D01*
G37*
G36*
G01X245385Y38847D02*
X241765D01*
G02Y41867I0J1510D01*
G01X245386D01*
G02X245385Y38847I-1J-1510D01*
G37*
G36*
G01X190267D02*
X186646D01*
G02X186647Y41867I1J1510D01*
G01X190267D01*
G02Y38847I0J-1510D01*
G37*
G36*
G01X174519D02*
X170898D01*
G02X170899Y41867I1J1510D01*
G01X174519D01*
G02Y38847I0J-1510D01*
G37*
G36*
G01X158771D02*
X155150D01*
G02X155151Y41867I1J1510D01*
G01X158771D01*
G02Y38847I0J-1510D01*
G37*
G36*
G01X143023D02*
X139403D01*
G02Y41867I0J1510D01*
G01X143024D01*
G02X143023Y38847I-1J-1510D01*
G37*
G36*
G01X127275D02*
X123655D01*
G02Y41867I0J1510D01*
G01X127276D01*
G02X127275Y38847I-1J-1510D01*
G37*
G36*
G01X111527D02*
X107907D01*
G02Y41867I0J1510D01*
G01X111528D01*
G02X111527Y38847I-1J-1510D01*
G37*
G36*
G01X95779D02*
X92158D01*
G02X92159Y41867I1J1510D01*
G01X95779D01*
G02Y38847I0J-1510D01*
G37*
G36*
G01X80031D02*
X76410D01*
G02X76411Y41867I1J1510D01*
G01X80031D01*
G02Y38847I0J-1510D01*
G37*
G36*
G01X319031Y236350D02*
X316069D01*
G02Y239050I-69J1350D01*
G01X319031D01*
G02Y236350I69J-1350D01*
G37*
G36*
G01X329939Y236762D02*
X329942Y236759D01*
X332041Y234668D01*
X332045Y234664D01*
G02X330148Y232742I-903J-1006D01*
G01X330145Y232745D01*
X328036Y234845D01*
X328033Y234848D01*
G02X329939Y236762I911J999D01*
G37*
G36*
G01X318550Y215231D02*
Y213169D01*
G02X315850I-1350J-69D01*
G01Y215231D01*
G02X318550I1350J69D01*
G37*
G36*
G01X322950Y210931D02*
Y208769D01*
G02X320250I-1350J-69D01*
G01Y210931D01*
G02X322950I1350J69D01*
G37*
G36*
G01X36300Y212127D02*
Y208373D01*
G02X33300I-1500J-73D01*
G01Y212127D01*
G02X36300I1500J73D01*
G37*
G36*
G01X33500Y203127D02*
Y199373D01*
G02X30500I-1500J-73D01*
G01Y203127D01*
G02X33500I1500J73D01*
G37*
G36*
G01X621522Y202461D02*
X617327Y198266D01*
G02X615361Y196093I-1227J-865D01*
G01X615228Y196167D01*
X606723Y187662D01*
X606822Y187524D01*
G02X604726Y185428I-1222J-874D01*
G01X604588Y185527D01*
X600319Y181258D01*
X600407Y181122D01*
G02X598328Y179043I-1257J-822D01*
G01X598192Y179131D01*
X596811Y177750D01*
X475181D01*
X475128Y177634D01*
G02X472672I-1228J566D01*
G01X472619Y177750D01*
X471681D01*
X471628Y177634D01*
G02X469172I-1228J566D01*
G01X469119Y177750D01*
X468181D01*
X468128Y177634D01*
G02X465672I-1228J566D01*
G01X465619Y177750D01*
X463189D01*
X462750Y178189D01*
Y178398D01*
X429749D01*
X427749Y176398D01*
X423143D01*
X422351Y176003D01*
X422249Y175900D01*
X422144D01*
X422141Y175898D01*
X422139D01*
X422046Y175852D01*
X421907Y175898D01*
X388751D01*
X385898Y178751D01*
Y198249D01*
X386898Y199249D01*
Y224040D01*
X386750Y224189D01*
Y224811D01*
X404189Y242250D01*
X468689D01*
X469689Y243250D01*
X533689D01*
X539250Y248811D01*
Y255311D01*
X560689Y276750D01*
X655811D01*
X665250Y267311D01*
Y259689D01*
X655750Y250189D01*
Y236689D01*
X624616Y205555D01*
X624707Y205419D01*
G02X621522Y202461I-1834J-1219D01*
G37*
G36*
G01X34850Y180100D02*
G03X34879Y179817I154J-127D01*
G02X33809Y175920I-1379J-1717D01*
G01X33637Y175895D01*
Y172000D01*
X20137D01*
Y194000D01*
X33637D01*
Y183653D01*
X33780Y183610D01*
G02X34850Y180100I-630J-2110D01*
G37*
G36*
G01X307505Y124052D02*
X307509D01*
X309573Y124142D01*
X309578D01*
G02X309696Y121444I122J-1346D01*
G01X309691D01*
X307626Y121354D01*
X307621Y121353D01*
G02X307505Y124052I-121J1347D01*
G37*
G36*
G01X307077Y119074D02*
X307081D01*
X309137Y119051D01*
X309142D01*
G02X309111Y116351I52J-1351D01*
G01X309107D01*
X307051Y116374D01*
X307046D01*
G02X307077Y119074I-52J1351D01*
G37*
G36*
G01X253427Y56400D02*
X250573D01*
G02Y59400I-73J1500D01*
G01X253427D01*
G02Y56400I73J-1500D01*
G37*
G36*
G01X261927Y56300D02*
X259073D01*
G02Y59300I-73J1500D01*
G01X261927D01*
G02Y56300I73J-1500D01*
G37*
G36*
G01X197627Y52900D02*
X194773D01*
G02Y55900I-73J1500D01*
G01X197627D01*
G02Y52900I73J-1500D01*
G37*
G36*
G01X181727D02*
X179073D01*
G02Y55900I-73J1500D01*
G01X181727D01*
G02Y52900I73J-1500D01*
G37*
G36*
G01X189627Y52800D02*
X186938D01*
G02Y55800I-73J1500D01*
G01X189627D01*
G02Y52800I73J-1500D01*
G37*
G54D41*
X37600Y198800D03*
Y203700D03*
X40400Y207800D03*
Y212700D03*
G54D39*
X144000Y67875D03*
Y147125D03*
G54D38*
X42717Y270472D03*
X235630Y75590D03*
X492520Y262598D03*
X761417Y22798D03*
G54D40*
X235630Y174016D03*
X498425Y22798D03*
X755512Y262598D03*
G54D37*
X42717Y191732D03*
G54D34*
X350197Y231103D03*
G54D35*
X11500Y68500D03*
X12000Y279000D03*
X816000Y280000D03*
G54D36*
X45669Y77185D03*
Y172460D03*
%LPC*%
G75*
G36*
G01X390724Y126400D02*
X390749D01*
X390780Y126431D01*
X390801Y126444D01*
G03X391256Y126899I-701J1156D01*
G01X391269Y126920D01*
X396249Y131900D01*
X409251D01*
X411751Y129400D01*
X431794D01*
X432502Y128849D01*
X432651Y128700D01*
X432694D01*
X432728Y128674D01*
X432937Y128700D01*
X436449D01*
X437649Y129900D01*
X442751D01*
X451251Y121400D01*
X463539D01*
X468189Y116750D01*
X623189D01*
X680250Y59689D01*
Y45311D01*
X677750Y42811D01*
Y31311D01*
X671250Y24811D01*
Y17811D01*
X668250Y14811D01*
Y11811D01*
X665689Y9250D01*
X600311D01*
X570311Y39250D01*
X533311D01*
X517311Y55250D01*
X449811D01*
X426811Y78250D01*
X396825D01*
X389600Y85957D01*
Y96749D01*
X384100Y102249D01*
Y125751D01*
X384749Y126400D01*
X389476D01*
X389516Y126380D01*
G03X390684I584J1220D01*
G01X390724Y126400D01*
G37*
G36*
G01X471252Y179250D02*
G03X469548I-852J-1050D01*
G01X467752D01*
G03X466048I-852J-1050D01*
G01X463599D01*
X463249Y179600D01*
X429251D01*
X427251Y177600D01*
X423097D01*
X422954Y177648D01*
X422858Y177600D01*
X422751D01*
X422645Y177493D01*
X421858Y177100D01*
X389249D01*
X387100Y179249D01*
Y197751D01*
X388100Y198751D01*
Y224039D01*
X404811Y240750D01*
X469311D01*
X470311Y241750D01*
X534311D01*
X540750Y248189D01*
Y254689D01*
X561311Y275250D01*
X655189D01*
X663750Y266689D01*
Y260311D01*
X654250Y250811D01*
Y237311D01*
X623301Y206362D01*
X623201Y206377D01*
G03X620696Y203872I-328J-2177D01*
G01X620711Y203772D01*
X615815Y198876D01*
X615759Y198863D01*
G03X614637Y197741I341J-1463D01*
G01X614624Y197685D01*
X604937Y187998D01*
X604910Y187984D01*
G03X604266Y187340I690J-1334D01*
G01X604252Y187313D01*
X598659Y181720D01*
X598619Y181705D01*
G03X597745Y180831I531J-1405D01*
G01X597730Y180791D01*
X596189Y179250D01*
X474752D01*
G03X473048I-852J-1050D01*
G01X471252D01*
G37*
%LPD*%
G75*
G54D15*
X17500Y190200D03*
X16844Y203100D03*
X13090Y231129D03*
Y234899D03*
X7600Y240861D03*
Y237091D03*
X13590Y242940D03*
Y254751D03*
X7600Y252672D03*
Y248902D03*
Y260713D03*
X13590Y258521D03*
Y246710D03*
X16900Y269000D03*
X7600Y264483D03*
X28400Y81400D03*
X30000Y136000D03*
X29700Y141200D03*
X26500Y181800D03*
X33500Y178100D03*
X33150Y181500D03*
X29400Y180000D03*
X23100Y181800D03*
X33500Y196100D03*
X32000Y203200D03*
Y199300D03*
X41200Y90300D03*
X42000Y96000D03*
X41500Y100800D03*
X40500Y124300D03*
X37600Y198800D03*
X37900Y195300D03*
X40400Y212700D03*
X34800Y208300D03*
X40400Y207800D03*
X34800Y212200D03*
X37600Y203700D03*
X44861Y227261D03*
X37900Y219000D03*
Y222500D03*
Y229500D03*
Y226000D03*
Y240000D03*
Y243500D03*
Y233000D03*
X38000Y236500D03*
X44400Y250400D03*
X37900Y257500D03*
Y254000D03*
Y247000D03*
X38000Y250500D03*
X46800Y274500D03*
X62900Y79900D03*
X60800Y87500D03*
X53500Y120400D03*
X57600Y136900D03*
X56100Y130700D03*
X52643Y130800D03*
X58000Y141750D03*
X58800Y177000D03*
X51860Y187640D03*
Y191410D03*
X59379Y184380D03*
X55720D03*
X57400Y210700D03*
X57009Y230009D03*
X57600Y226600D03*
X57500Y223200D03*
X57287Y219806D03*
X56724Y243300D03*
X56800Y249613D03*
X58102Y246471D03*
X57800Y253900D03*
X50000Y270000D03*
X57800Y264100D03*
X64700Y272500D03*
X57800Y267500D03*
X80031Y40357D03*
X76411D03*
X79700Y67500D03*
X79115Y60979D03*
X69235Y99735D03*
X68200Y94900D03*
Y91500D03*
X66500Y128000D03*
X65500Y123800D03*
X74800Y191000D03*
X72600Y244800D03*
X75600Y246700D03*
X79000Y246900D03*
X69400Y246000D03*
X75300Y259900D03*
X78200Y275600D03*
X71800Y268800D03*
X66800Y275200D03*
X74000Y271400D03*
X92159Y40357D03*
X88700Y54400D03*
X85300D03*
X90600Y63200D03*
X94000Y63300D03*
X82885Y60979D03*
X90000Y91000D03*
X91500Y84000D03*
X94500Y76200D03*
X89800Y87300D03*
X86100Y97700D03*
X90500Y101000D03*
X86500Y113500D03*
X80500D03*
X85500Y135400D03*
X83500Y191000D03*
X86900D03*
X84700Y197100D03*
X92900Y204008D03*
X89500Y204000D03*
X85898Y200598D03*
X95200Y216200D03*
X90812Y215000D03*
X80563Y214700D03*
X88900Y246700D03*
X82400Y246600D03*
X82100Y259600D03*
X80500Y269500D03*
X83900D03*
X95779Y40357D03*
X107907D03*
X109700Y60000D03*
X103450Y54400D03*
X100050D03*
X109600Y63700D03*
X96200Y60700D03*
X97900Y76200D03*
X106100Y158700D03*
X97100Y189200D03*
X110000Y201900D03*
X107740Y204460D03*
X102000Y203200D03*
X100600Y221100D03*
X110166Y239500D03*
X109500Y258300D03*
X97600Y246500D03*
X104900Y248800D03*
X120000Y40700D03*
X123655Y40357D03*
X111527D03*
X120200Y45610D03*
X119200Y57400D03*
X115800D03*
X111200Y67200D03*
X121170Y80900D03*
X121295Y77502D03*
X126000Y86200D03*
X125787Y78813D03*
X120700Y135500D03*
X118500Y125500D03*
X112550Y142800D03*
X119600Y143300D03*
X111900Y209000D03*
X112800Y225400D03*
X112700Y221200D03*
Y231400D03*
X136600Y44800D03*
X139403Y40357D03*
X127275D03*
X138000Y49800D03*
X138574Y57924D03*
X131600Y57400D03*
X135000D03*
X136469Y89902D03*
X130315Y90533D03*
X134200Y86100D03*
X137138Y76512D03*
X129300Y84900D03*
X136600Y93300D03*
X133558Y91779D03*
X136500Y104923D03*
X130000Y121000D03*
X136540Y108620D03*
X133975Y129141D03*
X130563Y125200D03*
X127500Y129180D03*
X126950Y125200D03*
X133786Y134700D03*
X130300Y135000D03*
X135412Y141400D03*
X138600Y146300D03*
X131500Y149000D03*
X136156Y138025D03*
X131762Y141796D03*
X127200Y158700D03*
X137300Y158900D03*
X140800D03*
X140000Y195500D03*
X137100Y188900D03*
X128000Y203300D03*
X143023Y40357D03*
X155151D03*
X144995Y57995D03*
X155290Y48610D03*
X143688Y48350D03*
X147400Y60400D03*
X147315Y54400D03*
X150715D03*
X153000Y67800D03*
X150894Y76497D03*
X154294Y76506D03*
X150670Y102720D03*
X154550Y106200D03*
X151080Y99344D03*
X154550Y102800D03*
X150670Y115500D03*
Y118900D03*
X157229Y119218D03*
X153693Y124807D03*
X147808Y145208D03*
X142900Y138595D03*
X146400D03*
X150804Y158896D03*
X144500Y158900D03*
X146980Y200580D03*
X153000Y201900D03*
X153500Y210000D03*
X146396Y207675D03*
X142997Y207891D03*
X150000Y210100D03*
X146500Y236500D03*
X146000Y231000D03*
X155300Y254000D03*
X144200Y270700D03*
X158771Y40357D03*
X170899D03*
X159060Y48610D03*
X170290Y49600D03*
X166463Y54400D03*
X163063D03*
X164000Y65000D03*
X172199Y91591D03*
X172300Y107189D03*
X158305Y112180D03*
X157500Y149025D03*
X158500Y161820D03*
X161900Y161700D03*
X167581Y164084D03*
X170910Y173840D03*
X167140D03*
X165900Y181500D03*
X163700Y178900D03*
X165700Y254000D03*
X174519Y40357D03*
X186647D03*
X174060Y49600D03*
X186865Y54300D03*
X181800Y54400D03*
X179000D03*
X179800Y65700D03*
X176900Y67500D03*
X180700Y78500D03*
X174900Y77700D03*
X183726Y106353D03*
X187500Y106500D03*
X173000Y97000D03*
X183344Y94056D03*
X179400Y94200D03*
X181732Y97500D03*
X178000Y97300D03*
X175787Y127000D03*
X176700Y144875D03*
X177200Y148700D03*
X181000Y167500D03*
X180931Y172985D03*
X177159Y172900D03*
X186300Y172400D03*
X174739Y207381D03*
X187000Y209500D03*
X198073Y40395D03*
X194445D03*
X190267Y40357D03*
X189700Y54300D03*
X197700Y54400D03*
X194700D03*
X190100Y68700D03*
X193500D03*
X194075Y80360D03*
X197845D03*
X202200Y89500D03*
X191500Y94100D03*
X188900Y91800D03*
X193005Y97155D03*
X195989Y95300D03*
X189106Y97235D03*
X201650Y111200D03*
X201899Y134200D03*
X194900Y124200D03*
X197140Y152010D03*
X194623Y149723D03*
X191200Y181068D03*
X199441Y187547D03*
X199392Y190947D03*
X202761Y186811D03*
X195630Y192770D03*
X198198Y206374D03*
X194800Y206100D03*
X201596Y206504D03*
X195000Y234000D03*
X205300Y54900D03*
X208700D03*
X214942Y67242D03*
X211600Y82100D03*
X212300Y85500D03*
X207200Y106000D03*
X209259Y113771D03*
Y117430D03*
X206605Y121741D03*
X209900Y120900D03*
X205380Y134200D03*
X210547Y139028D03*
X206790Y139040D03*
X215100Y194200D03*
X207861Y188540D03*
X215100Y199400D03*
X205000Y206500D03*
X215384Y202984D03*
X216000Y219500D03*
X208800D03*
X212500D03*
X206000Y234000D03*
X229300Y42950D03*
X232591Y43057D03*
X219900Y39100D03*
X223475Y53300D03*
X219899Y56800D03*
X233981Y59125D03*
X221400Y64500D03*
X230400Y63000D03*
X223800Y61700D03*
X230000Y66400D03*
X226500Y94450D03*
X227850Y97575D03*
X230875Y106300D03*
X227894Y104600D03*
X232600Y95300D03*
X227800Y101200D03*
X233452Y108588D03*
X228000Y108304D03*
Y139700D03*
X232921Y167505D03*
X227870Y170252D03*
X224200Y180200D03*
X232560Y204250D03*
X227000Y275500D03*
X236211Y43057D03*
X245385Y40357D03*
X241765D03*
X244400Y50600D03*
X235400Y63400D03*
X240297D03*
X243200Y73700D03*
X240300Y67200D03*
X246600Y73700D03*
X244759Y85200D03*
X236700Y88500D03*
X241200Y94900D03*
X244800Y100700D03*
X235075Y105600D03*
X234875Y139290D03*
Y143060D03*
X244715Y159785D03*
X239900Y180600D03*
X247596Y174667D03*
X240119Y183993D03*
X240100Y191000D03*
X246689Y196687D03*
X254600Y41100D03*
X265140Y40490D03*
X259000Y57800D03*
X250500Y57900D03*
X262000Y57800D03*
X253500Y57900D03*
X264500Y73100D03*
X253700Y75875D03*
X250300Y73800D03*
X264125Y79350D03*
X259820Y103454D03*
X262131Y100959D03*
X258634Y95850D03*
X263775Y140327D03*
X257977Y163423D03*
X264600Y173100D03*
X257687Y169870D03*
X253500Y174360D03*
X261300Y188300D03*
X253300Y189834D03*
X262700Y191500D03*
X261200Y209700D03*
X263600Y239850D03*
Y252700D03*
X257500Y266645D03*
X260500Y264630D03*
X269800Y44800D03*
X275300Y44900D03*
X278700Y44800D03*
X268910Y40490D03*
X278868Y56000D03*
X271000Y57500D03*
X268000D03*
X275200Y78700D03*
X275900Y88200D03*
X280100Y89100D03*
X272200Y108352D03*
X272185Y111831D03*
X278075Y116475D03*
X272300Y129442D03*
X268900Y129386D03*
X280400Y129225D03*
X272300Y149900D03*
X267187Y149800D03*
X278000Y141900D03*
X273900Y156198D03*
X270500Y163200D03*
X274100Y163300D03*
X267456Y160156D03*
X267100Y156200D03*
X272380Y159240D03*
X270500Y156250D03*
X268283Y173035D03*
X278300Y173300D03*
X276910Y189400D03*
X273060Y189374D03*
X266140Y191850D03*
X270341Y211835D03*
X278450Y216800D03*
X265259Y216659D03*
X270774Y222226D03*
X275400Y237900D03*
X267275Y253400D03*
X265500Y249300D03*
X269800Y250700D03*
X278700Y254240D03*
X275300Y254100D03*
X267000Y271300D03*
X284758Y40490D03*
X280988D03*
X286800Y57900D03*
X290200D03*
X288400Y94200D03*
X288100Y99500D03*
X281005Y99105D03*
X281475Y116475D03*
X286500Y119900D03*
X286600Y136000D03*
X287071Y173154D03*
X282950Y181350D03*
X282460Y189400D03*
X286300Y191885D03*
X293300Y212400D03*
X291201Y225025D03*
X287802Y225200D03*
X287600Y238100D03*
X287400Y254100D03*
X295500Y253500D03*
X281599Y261799D03*
X287250Y269250D03*
X296736Y40490D03*
X300506D03*
X300900Y46900D03*
X308200Y57400D03*
X304800D03*
X297150Y91100D03*
X309400Y82100D03*
X299800Y85950D03*
Y82300D03*
X304400Y88400D03*
X301300Y97000D03*
X301600Y93300D03*
X303400Y98500D03*
X303376Y95200D03*
X299300Y98500D03*
X296564Y136311D03*
Y127500D03*
X296531Y133061D03*
X301109Y146156D03*
X300700Y142850D03*
X297000Y160200D03*
X307231Y164059D03*
X310579Y182800D03*
X306612Y171882D03*
X304400Y182000D03*
X302591Y173906D03*
X309112Y171960D03*
X309200Y180500D03*
X305091Y173888D03*
X301745Y181788D03*
X307200Y182000D03*
X296600Y189100D03*
X305300Y203125D03*
X307300Y224900D03*
X304400D03*
X309900D03*
X298900Y253300D03*
X309400Y253600D03*
X306000D03*
X302600D03*
X304300Y262900D03*
X309000Y266700D03*
X311300Y277800D03*
X321900Y44000D03*
X312484Y40690D03*
X316254D03*
X314800Y48625D03*
X311950Y50800D03*
X320400Y48600D03*
X324000Y54900D03*
X324176Y48600D03*
X315800Y57400D03*
X319200D03*
X312400Y79700D03*
X312150Y100682D03*
X326000Y254100D03*
X315500D03*
X322500Y254200D03*
X319000D03*
X311400Y269200D03*
X326100Y267000D03*
X318600Y264300D03*
X313824Y280255D03*
X316945Y281606D03*
X316400Y276800D03*
X319400Y278800D03*
X322700Y277700D03*
X321600Y282500D03*
X325100Y281500D03*
X331931Y40995D03*
X328303D03*
X331300Y48475D03*
X327577D03*
X327400Y54900D03*
X333600Y63800D03*
X356432Y43657D03*
X356971Y37700D03*
X349900Y263800D03*
X342600Y277900D03*
X364600Y44298D03*
X367497Y41042D03*
X363604D03*
X371457Y37642D03*
X367520D03*
X366484Y47129D03*
X362626Y47068D03*
X366700Y68700D03*
X369500Y237200D03*
Y240600D03*
X373000Y242300D03*
X369500Y234600D03*
X373000Y236000D03*
Y238900D03*
X369500Y244000D03*
X385300Y47000D03*
X388000Y72963D03*
X382700Y275300D03*
X386100D03*
X379300D03*
X394229Y241128D03*
X391788Y238760D03*
X399438Y243839D03*
X401838Y246248D03*
X390500Y268800D03*
X393000Y275000D03*
X400900Y273000D03*
X391000Y265000D03*
X417000Y258000D03*
X416128Y272896D03*
X425400Y9103D03*
X422000D03*
X428800D03*
X432200D03*
X430000Y21500D03*
Y27358D03*
X424543Y22208D03*
Y27900D03*
X426405Y25054D03*
X427000Y17000D03*
X423500Y16885D03*
X423000Y43900D03*
X430000Y30758D03*
X424536Y34800D03*
X430000Y34158D03*
X424599Y31300D03*
X422986Y40350D03*
X430000Y244450D03*
X426600D03*
X420000Y244000D03*
X420500Y257800D03*
X433129Y245783D03*
X423600Y246700D03*
X423000Y274000D03*
X433300Y274100D03*
X426600D03*
X429900Y274940D03*
X442100Y7006D03*
X437061Y10393D03*
X434900Y6925D03*
X446800Y9900D03*
X438300Y6925D03*
X449600Y5900D03*
X446200D03*
X446100Y18700D03*
X441390Y28680D03*
X436240Y26300D03*
X449734Y18681D03*
X441281Y17025D03*
X436100Y30900D03*
X436106Y34506D03*
X435700Y243250D03*
X440600Y274300D03*
X449400Y273700D03*
X436600Y275000D03*
X450200Y9800D03*
X451300Y21700D03*
X464000Y275200D03*
X460400D03*
X452500D03*
X469000D03*
X472400Y275100D03*
X466500Y272800D03*
X472101Y266090D03*
X475500Y265900D03*
X479000D03*
X493000Y119299D03*
X495400Y183500D03*
X482400Y266200D03*
X502000Y89000D03*
X498500Y88995D03*
X508000Y119500D03*
X511500D03*
X511200Y183400D03*
X500900D03*
X504400D03*
X510675Y209700D03*
X505315Y268500D03*
X497002Y275400D03*
X525740Y88960D03*
X522280Y89810D03*
X515502Y88998D03*
X518902Y88987D03*
X518200Y183400D03*
X526600Y183500D03*
X514800Y183400D03*
X513100Y234500D03*
X516500D03*
X528985Y89975D03*
X533267Y89634D03*
X539574Y88990D03*
X533000Y119500D03*
X536400D03*
X528100D03*
X528400Y145041D03*
X541550Y183550D03*
X534750Y183600D03*
X538150D03*
X530214Y183481D03*
X531500Y219500D03*
X541500Y234900D03*
X551800Y69600D03*
X548400Y69700D03*
X555199D03*
X556500Y89000D03*
X546349Y89512D03*
X552900Y89100D03*
X542950Y89400D03*
X555500Y183500D03*
X548354Y183600D03*
X544954D03*
X551754D03*
X548300Y209700D03*
X551700Y209800D03*
X550400Y222285D03*
X561999Y69700D03*
X558599D03*
X570715Y89100D03*
X566000D03*
X572845Y183300D03*
X566897Y183405D03*
X561900Y183600D03*
X564398Y183481D03*
X569395Y183300D03*
X558915Y183603D03*
X558300Y210000D03*
X561000Y222700D03*
X561196Y227366D03*
X569200Y223600D03*
X564200Y224000D03*
X575000Y89100D03*
X587500Y88913D03*
X578400Y89100D03*
X588600Y124700D03*
X584800Y183300D03*
X582254Y183313D03*
X576295Y183400D03*
X588475Y183300D03*
X578795D03*
X573600Y190100D03*
X586800Y213200D03*
X583800Y207200D03*
X580350Y207250D03*
X599500Y87500D03*
X590898Y89045D03*
X596845Y89624D03*
X593400Y126000D03*
X592200Y145000D03*
X595744Y145041D03*
X599150Y180300D03*
X593475Y183275D03*
X601750Y182500D03*
X590975Y183275D03*
X594350Y187725D03*
X591850D03*
X588800Y205900D03*
X591363Y208387D03*
X602800Y203225D03*
X601200Y207700D03*
X603964Y210400D03*
X612120Y121750D03*
X608360Y121800D03*
X608300Y144890D03*
X618500Y159000D03*
X605600Y186650D03*
X609345Y190100D03*
X607500Y188300D03*
X616100Y197400D03*
X634000Y97500D03*
X630700Y100500D03*
X627500Y104900D03*
X620000Y112575D03*
X624726Y107395D03*
X621100Y124900D03*
X625500Y159000D03*
X629000D03*
X622000D03*
X633319Y155008D03*
X631900Y175850D03*
X634748Y177708D03*
X633100Y198300D03*
X626300Y198250D03*
X629700Y198300D03*
X622873Y204200D03*
X642823Y88477D03*
X640677Y91115D03*
X638500Y94000D03*
X635000Y110500D03*
X638000Y107400D03*
X648500Y144000D03*
X636719Y154972D03*
X643500Y155000D03*
X640110Y155272D03*
X640461Y181410D03*
X642600Y186400D03*
X646000D03*
X636500Y198300D03*
X653600Y122400D03*
X656477Y148033D03*
X656642Y151430D03*
X656200Y144000D03*
X650500Y155000D03*
X661000Y173800D03*
X657722Y193800D03*
X661600Y197300D03*
X654851Y191978D03*
X663800Y199900D03*
X673100Y179455D03*
X673044Y190456D03*
X668732Y204555D03*
X666446Y202037D03*
X682600Y114300D03*
X689400Y178900D03*
X689547Y175500D03*
X686700Y187400D03*
X687456Y183944D03*
X705145Y93500D03*
X707209Y97500D03*
X698970Y118149D03*
X699241Y114759D03*
X709500Y143500D03*
X709900Y139900D03*
X701245Y183800D03*
X718900Y94000D03*
X726800Y95500D03*
X724200Y108400D03*
X714000Y118500D03*
X727448Y128893D03*
X714900Y131900D03*
X718200Y147000D03*
Y150400D03*
X718825Y155453D03*
X712700Y155978D03*
X724400Y176025D03*
X725500Y195500D03*
X727400Y227400D03*
X736900Y98500D03*
X730200Y94900D03*
X742100Y118200D03*
X736300Y118000D03*
X729400Y120200D03*
X732000Y122700D03*
X728900Y132976D03*
X727800Y136600D03*
X740300Y164700D03*
X727800Y176600D03*
X733000Y176200D03*
X739900Y212800D03*
X731000Y210200D03*
X739800Y216300D03*
X750100Y16100D03*
X749500Y101500D03*
X751300Y118200D03*
X754000Y115100D03*
X748800Y115800D03*
X757900Y124700D03*
X743100Y195500D03*
X743000Y211000D03*
X744100Y221900D03*
X743800Y215900D03*
X758916Y104250D03*
X762304Y103957D03*
X765500Y112000D03*
X769800Y133000D03*
X759400Y131000D03*
X771300Y140200D03*
X766600Y139800D03*
X762000Y281000D03*
X765400D03*
X774500Y31307D03*
X778000D03*
X787600Y183300D03*
X787800Y179900D03*
X793000Y174500D03*
X805500Y128000D03*
G54D20*
X196800Y62600D03*
X199600Y160100D03*
X502500Y6200D03*
X538300Y15200D03*
X699000Y162255D03*
X756400Y110500D03*
X786500Y13500D03*
X782000Y137000D03*
X790500Y11000D03*
X799000Y121500D03*
Y125500D03*
X800400Y158500D03*
X799900Y168800D03*
X811000Y130000D03*
Y134000D03*
X809000Y149200D03*
X811000Y138000D03*
X811200Y141600D03*
X809500Y156900D03*
X809600Y160500D03*
X809700Y164300D03*
G54D13*
X15400Y118000D03*
X10900D03*
X15500Y122800D03*
X15000Y127500D03*
X11000Y122800D03*
X10500Y127500D03*
X11500Y163700D03*
Y159000D03*
X7000Y163700D03*
Y159000D03*
X33000Y105000D03*
X30200Y145000D03*
Y149200D03*
X34000Y161500D03*
X30300Y157600D03*
X30200Y153400D03*
X37500Y105000D03*
X42000D03*
X37500Y264000D03*
X63500Y43500D03*
Y57500D03*
Y48000D03*
Y52500D03*
X63200Y194900D03*
X68500Y47500D03*
X73500Y48000D03*
X68000Y52500D03*
X70900Y193800D03*
X82000Y177500D03*
X92800Y285600D03*
X104000Y106600D03*
Y115500D03*
Y111000D03*
X100000Y267400D03*
X100700Y262900D03*
X97500Y285450D03*
X102000D03*
X106500Y285550D03*
X110700D03*
X119400Y106700D03*
X123800Y102500D03*
X123900Y106700D03*
X119400Y102300D03*
Y115900D03*
Y111200D03*
X123900Y115900D03*
Y111200D03*
X113200Y146700D03*
X113100Y151000D03*
X117500Y146950D03*
X119000Y159100D03*
X114700Y158800D03*
X116500Y211200D03*
X134100Y96600D03*
X128500Y165000D03*
X129500Y252500D03*
X129000Y268000D03*
X166500Y241000D03*
X189000Y87700D03*
X192500Y161900D03*
X192600Y166700D03*
X201200Y164200D03*
X216261Y74846D03*
X212300Y157300D03*
X212600Y161500D03*
X217000Y252900D03*
X217200Y258000D03*
X226900Y133300D03*
X234525Y239250D03*
X229700Y234700D03*
X225300Y239200D03*
X234525Y243450D03*
X229725D03*
X225300Y243400D03*
X234525Y234800D03*
X225300D03*
X229675Y239000D03*
X221300Y255400D03*
X240130Y77300D03*
X236400Y95100D03*
X240565Y113365D03*
X249350Y199400D03*
X247500Y239250D03*
X243300Y235050D03*
X247500Y243450D03*
X243300D03*
X238900D03*
X243300Y239250D03*
X247500Y235050D03*
X238925Y235000D03*
Y239200D03*
X258400Y65600D03*
X252350Y202350D03*
X251700Y239250D03*
Y243450D03*
X253000Y267000D03*
X278200Y281350D03*
X294800Y94100D03*
X282686Y281336D03*
X339638Y67138D03*
X334500Y266300D03*
X334300Y270500D03*
X335700Y278751D03*
X331500D03*
X345089Y73089D03*
X353500Y71900D03*
X357000Y69500D03*
X349300Y83000D03*
X345100D03*
X354200Y76400D03*
X343600Y270500D03*
X371400Y42500D03*
X371500Y47000D03*
X359800Y72700D03*
X362700Y69600D03*
X380000Y38100D03*
X375600Y42500D03*
X380300D03*
X375700Y47000D03*
X380295Y46779D03*
X505200Y215000D03*
X496711Y248999D03*
X527000Y225500D03*
X600900Y230200D03*
X615700D03*
X630000Y55300D03*
X623400Y230100D03*
X640500Y55000D03*
X655133Y55833D03*
X721200Y65100D03*
X732000Y63500D03*
X753500Y24007D03*
Y20007D03*
Y28507D03*
X755500Y16000D03*
X770500Y13007D03*
X767500Y24007D03*
X760500Y29000D03*
X761000Y16007D03*
X767500Y28507D03*
Y19507D03*
X764200Y44200D03*
X767500Y33207D03*
X759000Y37507D03*
X764500Y54000D03*
X764300Y49200D03*
X769500Y50000D03*
X761000Y58500D03*
X787500Y93000D03*
X783000D03*
X785830Y188700D03*
X785400Y202800D03*
X789000Y204979D03*
X789200Y214200D03*
Y209800D03*
X784500Y222500D03*
X789000Y223500D03*
X789200Y218700D03*
X786000Y228000D03*
Y232400D03*
X786200Y236900D03*
X786300Y241500D03*
X785000Y245800D03*
Y250200D03*
Y254900D03*
X792000Y83000D03*
X796500D03*
X792000Y87700D03*
X796500D03*
X799200Y98600D03*
X803100Y106000D03*
X799200Y102800D03*
X799000Y107100D03*
X803500Y116700D03*
Y112500D03*
X799000Y116100D03*
Y111900D03*
X789910Y187679D03*
X794110D03*
X798310Y187779D03*
X793500Y204979D03*
Y223500D03*
X793200Y228400D03*
Y232600D03*
Y237200D03*
Y242400D03*
X793300Y247200D03*
X795300Y260800D03*
X795400Y251700D03*
X795300Y256500D03*
Y265000D03*
X810100Y275000D03*
X812035Y271067D03*
X810100Y267339D03*
X812000Y263500D03*
G54D18*
X42717Y270472D03*
X235630Y75590D03*
X492520Y262598D03*
D03*
X761417Y22798D03*
D03*
X794032Y27032D03*
X804032Y37032D03*
Y47032D03*
X794032Y37032D03*
Y47032D03*
X804032Y57032D03*
X794032D03*
Y67032D03*
G54D22*
X235630Y174016D03*
X498425Y22798D03*
D03*
X755512Y262598D03*
D03*
G54D24*
X303610Y110800D03*
X309000Y114700D03*
X306700D03*
X309194Y117700D03*
X306994Y117725D03*
X304149Y128349D03*
X307854Y130539D03*
X309700Y122796D03*
X309500Y132925D03*
X307298Y132697D03*
X307500Y122700D03*
X305050Y151150D03*
X309000Y137600D03*
X306961Y153717D03*
X306696Y158610D03*
X309000Y158806D03*
X309220Y153698D03*
X305800Y195400D03*
X303500D03*
X303480Y189100D03*
X301300Y188700D03*
X309700Y187997D03*
X307500Y188000D03*
X317641Y90956D03*
X325081Y100631D03*
X322075Y100650D03*
X323120Y92400D03*
X319520Y92419D03*
X318900Y98000D03*
X317600Y93625D03*
X326162Y91438D03*
X315950Y98650D03*
X320992Y112180D03*
X319096Y113300D03*
X319418Y123225D03*
X315451Y123219D03*
X323900Y129900D03*
X325418Y127349D03*
X325746Y133702D03*
X323300Y147046D03*
X326322Y138434D03*
X325763Y141958D03*
X325200Y149319D03*
X319704Y162804D03*
X323000Y153900D03*
X324029Y166384D03*
X326234Y153969D03*
X323500Y180063D03*
X323121Y182913D03*
X326408Y182292D03*
X316844Y196010D03*
X319801Y194890D03*
X326550Y191600D03*
X322256Y198618D03*
X323331Y196696D03*
X325642Y202325D03*
X321600Y208700D03*
Y211000D03*
X317200Y213100D03*
Y215300D03*
X316000Y237700D03*
X319100D03*
X329300Y87300D03*
X331200Y88600D03*
X330100Y100200D03*
Y98000D03*
X336750Y93500D03*
Y95704D03*
X328000Y92700D03*
X330900Y93400D03*
X333313Y103693D03*
X329415Y119923D03*
X333601Y120500D03*
X333534Y118040D03*
X333434Y106668D03*
X341200Y112569D03*
X338768Y116755D03*
Y119755D03*
X329308Y122386D03*
X338329Y135665D03*
X329031Y125428D03*
X335303Y135178D03*
X336900Y127600D03*
X333977Y127678D03*
X327854Y130434D03*
X338470Y138177D03*
X335450Y150900D03*
X327963Y142008D03*
X335514Y138220D03*
X338320Y141300D03*
X327390Y149106D03*
X336920Y146130D03*
X329421Y138228D03*
X327696Y146108D03*
X330163Y142008D03*
X332478Y138255D03*
X341342Y138224D03*
X333750Y145950D03*
X339491Y143163D03*
X329800Y150800D03*
X332000D03*
X330300Y158546D03*
X339784Y161847D03*
X335499Y153846D03*
X327800Y161500D03*
X336900Y161600D03*
X336800Y164434D03*
X341390Y153991D03*
X329161Y153830D03*
X335964Y158512D03*
X341400Y156700D03*
X331000Y164500D03*
X330900Y161700D03*
X333000Y158300D03*
X339747Y164478D03*
X339300Y174100D03*
X330821Y177402D03*
X329442Y169463D03*
X327708Y177241D03*
X332353Y169522D03*
X337000Y174102D03*
X327600Y174174D03*
X330027Y174119D03*
X334700Y174100D03*
X336915Y177423D03*
X337863Y180545D03*
X330280Y180900D03*
X332500D03*
X335400Y196300D03*
X337800Y189200D03*
X326850Y193900D03*
X329972Y196400D03*
Y193559D03*
X333996Y192063D03*
X334707Y189383D03*
X337800Y192200D03*
X329313Y188000D03*
X335739Y199317D03*
X336500Y204600D03*
X338926Y211674D03*
X338967Y209455D03*
X331658Y212660D03*
X327216Y203902D03*
X328510Y218320D03*
X327024Y220024D03*
X337307Y217961D03*
X331616Y214860D03*
X337341Y215731D03*
X328945Y235846D03*
X331142Y233658D03*
X346596Y118163D03*
Y115163D03*
X343570Y112561D03*
X346495Y130000D03*
X349149Y124141D03*
X351500Y136000D03*
X343000Y126200D03*
X343146Y128473D03*
X347641Y133479D03*
X342533Y133822D03*
X357300Y128600D03*
X355400Y137100D03*
X354300Y128600D03*
X346300Y143000D03*
X355447Y146528D03*
X344500Y141700D03*
X348675Y143326D03*
X348743Y146072D03*
X346000Y146043D03*
X346450Y149120D03*
X348432Y164844D03*
X346944Y156775D03*
X350550Y153280D03*
X344300Y153800D03*
X344090Y156690D03*
X352000Y162000D03*
X348700Y161700D03*
X351600Y164300D03*
X355400Y152900D03*
X350700Y155600D03*
X345900Y161700D03*
X342188Y183361D03*
X347200Y174300D03*
X344165Y169466D03*
X352200Y171800D03*
X347500Y169500D03*
X351600Y169600D03*
X353302Y182993D03*
X342233Y185639D03*
X356900Y186100D03*
X349600Y194800D03*
X342339Y192225D03*
X342342Y190024D03*
X349100Y191900D03*
X353625Y195045D03*
Y192045D03*
X356600Y195700D03*
X356700Y193300D03*
X345503Y193474D03*
X345500Y190500D03*
X349100Y189700D03*
X353342Y186124D03*
X345500Y184500D03*
X345631Y187420D03*
X353594Y210707D03*
X347593Y210277D03*
X353385Y212898D03*
X343242Y213690D03*
X347664Y212476D03*
X343198Y215910D03*
X371900Y85400D03*
X364800Y91200D03*
X368600Y90700D03*
X361200Y90200D03*
X371950Y92500D03*
X364874Y98250D03*
X362803Y106035D03*
X357900Y99200D03*
X368600Y97500D03*
X357721Y91779D03*
X361200Y97500D03*
X365316Y108130D03*
X372700Y119663D03*
X370100Y119563D03*
X370000Y116563D03*
X362111Y127142D03*
X362120Y124153D03*
X359421Y127128D03*
Y124008D03*
X372821Y125628D03*
X370121Y125528D03*
X367321Y122528D03*
X368026Y137118D03*
X364700Y134000D03*
X367992Y133982D03*
X359300Y130000D03*
X367900Y152550D03*
X368000Y146500D03*
X361700Y143300D03*
X364886Y140268D03*
X368026D03*
Y143418D03*
X364621Y143328D03*
X361500Y149500D03*
X368026Y149718D03*
X368100Y165300D03*
X364600D03*
X367950Y159200D03*
X371157Y162320D03*
X371176Y158940D03*
X358477Y159300D03*
X361600Y159250D03*
X358500Y155700D03*
X371100Y168700D03*
X364600Y174800D03*
X361500Y175000D03*
Y168500D03*
X367906Y171458D03*
X364600Y171600D03*
X364607Y177103D03*
X370900Y171700D03*
X361200Y178500D03*
X372400Y179100D03*
X369021Y180128D03*
X372600Y181400D03*
X364792Y188743D03*
X364600Y186138D03*
X364895Y190941D03*
X369106Y191903D03*
X369200Y189100D03*
X361257Y193524D03*
Y190700D03*
X364947Y193141D03*
X372700Y213700D03*
X369450Y212040D03*
X358498Y210220D03*
X358382Y212427D03*
X372800Y221600D03*
X369580Y218800D03*
X357966Y217516D03*
X359827Y216341D03*
X383350Y83350D03*
X383450Y90500D03*
X387200D03*
X387100Y83500D03*
X375800D03*
Y90500D03*
X379500Y83302D03*
Y90600D03*
X381600Y119900D03*
X381900Y113000D03*
X382596Y108600D03*
X385600Y116500D03*
X385200Y113137D03*
X385721Y119528D03*
X386561Y108812D03*
X385479Y125569D03*
X381500Y123200D03*
X381600Y126427D03*
X385523Y122532D03*
X386708Y137118D03*
X383567Y137096D03*
X380475Y137016D03*
X380443Y130102D03*
X374200Y136994D03*
X380398Y146568D03*
X383548D03*
X374200Y140144D03*
X380400Y152700D03*
X383575Y149603D03*
X380522Y149564D03*
X386853Y149640D03*
X377476Y149688D03*
X374200Y149494D03*
X374100Y159150D03*
X386800Y165300D03*
X380398Y165240D03*
X383781Y165235D03*
X386777Y159005D03*
X380500Y162025D03*
X383700Y162199D03*
X383500Y159000D03*
X374300Y155800D03*
X377500Y165240D03*
X384740Y180080D03*
X381720Y180220D03*
X381800Y183300D03*
X380540Y177370D03*
X383693Y171424D03*
X386600Y174900D03*
X380477Y171605D03*
X376830Y175640D03*
X381460Y195610D03*
X384390Y196470D03*
X381140Y187960D03*
X381280Y191550D03*
X384708Y188910D03*
X384600Y186100D03*
X373922Y193103D03*
X374000Y190350D03*
X379750Y213500D03*
X376300Y211000D03*
X382600Y222600D03*
X382750Y229000D03*
X379700Y219200D03*
X385947Y226500D03*
X385900Y218400D03*
X376300Y216200D03*
X390700Y89300D03*
X403726Y83826D03*
X403700Y90200D03*
X397300Y89168D03*
X400400Y92200D03*
Y98500D03*
X390750Y96500D03*
X394100Y91400D03*
Y99000D03*
X397100Y96600D03*
X397300Y93100D03*
X392382Y102149D03*
X390650Y93000D03*
X394100Y94900D03*
X400400Y95000D03*
X393331Y118043D03*
X393351Y115107D03*
X397650Y115500D03*
X401749Y112418D03*
X401159Y119636D03*
X401353Y116562D03*
X396276Y120948D03*
X396251Y117999D03*
X396600Y112463D03*
X390683Y108042D03*
X400700Y108800D03*
X389700Y112363D03*
X398500Y125604D03*
X398512Y122815D03*
X401500Y125600D03*
X393482Y123982D03*
X396700Y128000D03*
X389914Y124536D03*
X390100Y127600D03*
X390205Y133858D03*
X392998Y133968D03*
X396148D03*
X396321Y136987D03*
X402561Y137000D03*
X399298Y137118D03*
X392998D03*
X389848D03*
X402400Y140163D03*
X393000Y152663D03*
X402900Y149663D03*
X396148Y140268D03*
X399298D03*
X389848Y146568D03*
X393204Y146436D03*
X403080Y146931D03*
X399198Y146468D03*
X396192Y146444D03*
X392998Y149718D03*
X399198Y149618D03*
X396182Y149674D03*
X396200Y152763D03*
X396300Y162100D03*
X399300Y152863D03*
Y155963D03*
X392998Y165240D03*
X393028Y162059D03*
X393198Y158940D03*
X403078Y152922D03*
X402373Y155952D03*
X399298Y162090D03*
X402505Y159133D03*
X396148Y158940D03*
X399298D03*
X392599Y181686D03*
X400252Y182966D03*
X403600Y182400D03*
Y180200D03*
X402540Y171760D03*
X402600Y174611D03*
X396000Y179000D03*
X399385Y171686D03*
X396225D03*
X390025Y174672D03*
X393085Y171686D03*
Y174836D03*
X397100Y181000D03*
X400301Y186099D03*
X397805Y192061D03*
X392600Y190600D03*
X396200Y194700D03*
X392624Y184537D03*
X389500Y193600D03*
X397307Y186607D03*
X395600Y184100D03*
Y190300D03*
X392700Y193563D03*
X403022Y192094D03*
X402967Y195005D03*
X389484Y190442D03*
X389300Y187700D03*
X392100Y213700D03*
X395700Y213600D03*
X400400Y209400D03*
X398500Y208000D03*
X389100Y224000D03*
X399700Y225000D03*
Y216400D03*
X395600Y224400D03*
X395700Y217000D03*
X391950Y220800D03*
X392000Y217200D03*
X395700Y220600D03*
X399800D03*
X389150Y230300D03*
X407500Y84000D03*
X407400Y91000D03*
X411300Y85600D03*
X414722Y90250D03*
X414300Y85600D03*
X403800Y87000D03*
X407400Y87400D03*
X411000Y88900D03*
X418300Y91300D03*
X418400Y98150D03*
X411000Y92100D03*
X414622Y98000D03*
X414672Y94500D03*
X417800Y100400D03*
X412650Y100197D03*
X418300Y94800D03*
X407550Y100196D03*
X404529Y118507D03*
X405900Y121700D03*
X409110Y114910D03*
X405200Y115343D03*
X412462Y115713D03*
X409196Y118195D03*
X416904Y119591D03*
X413100Y121800D03*
X404900Y124600D03*
X416000Y135983D03*
X415000Y131400D03*
X408956Y130064D03*
X418500Y128200D03*
X415100Y127900D03*
X406200Y127400D03*
X416851Y122600D03*
X412462Y126300D03*
X405500Y131063D03*
X414900Y147000D03*
X417900Y146900D03*
X408800Y147000D03*
X411900Y146800D03*
X413300Y139100D03*
X413400Y142700D03*
X418000Y142500D03*
X406000Y150200D03*
X407500Y152100D03*
X410400Y152000D03*
X418439Y167118D03*
X414800Y162600D03*
X411800Y162700D03*
X414572Y165913D03*
X411356Y165732D03*
X407500Y157600D03*
X412900Y157800D03*
X407400Y154863D03*
X406100Y159500D03*
X415100Y158100D03*
X410272Y154794D03*
X416400Y155000D03*
X408600Y159600D03*
X411600D03*
X409300Y167163D03*
X404558Y154835D03*
X407100Y167429D03*
X418600Y182800D03*
X414960Y178130D03*
X414950Y181460D03*
X411260Y178090D03*
X411553Y181222D03*
X416400Y170300D03*
X413265Y170423D03*
X410620Y173300D03*
X408158Y178666D03*
X417900Y178363D03*
X415992Y189254D03*
Y186205D03*
X419097Y189563D03*
X416500Y195563D03*
X408242Y184624D03*
X405231Y184976D03*
X408200Y190500D03*
X408100Y193600D03*
X412500Y197300D03*
X405000Y190700D03*
X412100Y190400D03*
X411342Y185024D03*
X405800Y196700D03*
X412200Y192600D03*
X416900Y200100D03*
X416353Y207249D03*
X408200Y226900D03*
X408100Y220500D03*
X404400Y228600D03*
Y222300D03*
X415600Y222700D03*
X415800Y215900D03*
X412050Y225100D03*
X412100Y218400D03*
X408200Y223800D03*
X412000Y222000D03*
X415700Y219200D03*
X404400Y225300D03*
X422078Y97678D03*
X422000Y91300D03*
X427560Y104770D03*
X429105Y106337D03*
X429500Y93800D03*
X434021Y100128D03*
X422050Y94800D03*
X428100Y120000D03*
X424900Y121213D03*
X420600Y118300D03*
X420672Y120600D03*
X422042Y115224D03*
X424700Y115000D03*
X427900Y114300D03*
X428100Y116500D03*
X430302Y112098D03*
X419596Y113463D03*
X428255Y126236D03*
X425000Y135350D03*
X419500Y136400D03*
X430100Y131500D03*
X431700Y128300D03*
X423500Y128200D03*
X427000Y128050D03*
X423900Y131500D03*
X420942Y131324D03*
X431504Y126061D03*
X424982Y126500D03*
X427600Y143841D03*
X421500Y142400D03*
X426900Y147100D03*
X431100Y145500D03*
X424856Y142270D03*
X422400Y139000D03*
X420861Y149687D03*
Y146923D03*
X430694Y142275D03*
X428390Y139059D03*
X423945Y165221D03*
X421710Y167230D03*
X431130Y166660D03*
X428238Y167709D03*
X420804Y162659D03*
X420900Y160037D03*
X425500Y154737D03*
X428400D03*
X434500Y160037D03*
X430360Y181350D03*
X430340Y177620D03*
X423642Y181374D03*
X426970Y178310D03*
X425400Y170240D03*
X428500Y173120D03*
X422337Y170575D03*
X425427Y173113D03*
X419453Y173187D03*
X420922Y178117D03*
X423842Y178274D03*
X428431Y170264D03*
X432100Y190400D03*
X429100Y189696D03*
X426173Y190784D03*
X428830Y195379D03*
X422152Y189600D03*
X420800Y193100D03*
X421171Y196496D03*
X431270Y193425D03*
X425500Y186045D03*
X429933Y197283D03*
X420975Y211300D03*
X427900Y202800D03*
X424832Y200174D03*
X421811Y202603D03*
X421253Y199822D03*
X425642Y209524D03*
X419550Y222700D03*
X419600Y216200D03*
Y219200D03*
X444578Y106201D03*
X442378Y106198D03*
X440178Y106200D03*
X437400Y121600D03*
X442842Y120824D03*
X438700Y112900D03*
X438500Y116400D03*
X439400Y120100D03*
X434960Y114529D03*
X444242Y124324D03*
X435442Y124024D03*
X437800Y128100D03*
X434700Y128200D03*
X443400Y148900D03*
X437472Y152501D03*
X434834Y163817D03*
X439600Y153800D03*
X435105Y181207D03*
X438742Y197224D03*
X435642Y194824D03*
X437921Y192956D03*
X445000Y194500D03*
X443100Y195900D03*
X443000Y192700D03*
X435453Y185397D03*
X436957Y209867D03*
X459800Y118800D03*
X453000Y118700D03*
X456200Y118900D03*
X459700Y129900D03*
X452200Y129800D03*
X463100Y133700D03*
X456000Y133500D03*
X460100Y123100D03*
X453000Y123300D03*
X463200Y126200D03*
X456500Y126100D03*
X461200Y167400D03*
X454200D03*
X464300Y181800D03*
X458000Y171100D03*
X451000D03*
X460000Y174900D03*
X453000D03*
X457400Y197000D03*
X450400D03*
X462500Y189000D03*
X460400Y193300D03*
X453400D03*
X456900D03*
X453900Y197000D03*
X459500Y200700D03*
X452500D03*
X456000D03*
X473900Y178200D03*
X466900D03*
X471300Y181800D03*
X470400Y178200D03*
X467800Y181800D03*
X473100Y185500D03*
X466000D03*
X469500Y189000D03*
X469600Y185500D03*
X466000Y189000D03*
X504000Y12507D03*
X508700Y14607D03*
X511589Y30295D03*
X507839Y30362D03*
X506496Y272500D03*
X523453Y12360D03*
X511800Y12507D03*
X520700Y14807D03*
X518769Y22907D03*
X515484D03*
X525753Y30893D03*
X522733Y32832D03*
X511640Y255956D03*
X514137Y256089D03*
X522908Y255117D03*
X526715Y254700D03*
X511736Y273001D03*
X514900Y271350D03*
X522992Y270700D03*
X525845Y272863D03*
X517846Y262489D03*
X521131D03*
X528525Y12549D03*
X542100Y15107D03*
X530700Y15407D03*
X536485Y22907D03*
X533200D03*
X542407Y30882D03*
X532350Y30807D03*
X529120Y32575D03*
X530015Y255000D03*
X531775Y252231D03*
X541005Y254800D03*
X540900Y252300D03*
X530900Y273000D03*
X534100Y270700D03*
X541500Y270900D03*
X535562Y262489D03*
X538847D03*
X550000Y12507D03*
X544860Y12407D03*
X552800Y14807D03*
X557745Y22907D03*
X554460D03*
X553079Y30712D03*
X549500Y31607D03*
X545928Y31047D03*
X544800Y255100D03*
X550200Y255500D03*
X551000Y252056D03*
X552800Y255300D03*
X545500Y252600D03*
X553485Y252332D03*
X544292Y273128D03*
X548800Y271000D03*
X551937Y272789D03*
X555641Y262489D03*
X554500Y264900D03*
X568555Y12407D03*
X561200Y12507D03*
X571600Y14207D03*
X564400Y14307D03*
X570852Y33204D03*
X569800Y29807D03*
X565091Y30815D03*
X561456Y30902D03*
X561419Y254850D03*
X565054Y254773D03*
X568327Y253348D03*
X571867Y254685D03*
X560555Y252503D03*
X563376Y256627D03*
X566151Y252115D03*
X572150Y252200D03*
X560600Y270300D03*
X564100Y271100D03*
X567800Y270500D03*
X570200Y273100D03*
X558926Y262489D03*
X570200Y269700D03*
X559600Y272900D03*
X572155Y264900D03*
X565700Y273050D03*
X559700Y264900D03*
X572700Y273100D03*
X587940Y12417D03*
X582655Y12407D03*
X579800Y14807D03*
X577824Y22907D03*
X574539D03*
X583700Y28207D03*
X585179Y30867D03*
X581450Y30707D03*
X579100Y33207D03*
X585550Y33340D03*
X587700Y255300D03*
X579205Y254850D03*
X582200Y252206D03*
X587642D03*
X582300Y254900D03*
X578800Y252200D03*
X580200Y273000D03*
X582600Y270300D03*
X588036Y273089D03*
X588400Y270300D03*
X573357Y262489D03*
X576642D03*
X577450Y264900D03*
X580107Y270501D03*
X577636Y272947D03*
X594600Y6707D03*
X600896Y12407D03*
X601704Y22907D03*
X601000Y20507D03*
X594400Y36207D03*
X589300Y33007D03*
X590500Y30507D03*
X594200Y33607D03*
X600360Y33287D03*
X594600Y260000D03*
X591300Y255010D03*
X590837Y259889D03*
X598398Y260199D03*
X591342Y252206D03*
X594500Y265200D03*
X591500Y270100D03*
X591536Y273000D03*
X590700Y264833D03*
X598300Y265400D03*
X610952Y12307D03*
X616600D03*
X605700Y12407D03*
X615852Y19807D03*
X615907Y24856D03*
X607300Y14507D03*
X616707Y15616D03*
X604989Y22907D03*
X610800Y14807D03*
X605728Y20518D03*
X612000Y17407D03*
X610944Y33333D03*
X607800Y30407D03*
X618900Y33290D03*
X615103Y30690D03*
X610500Y30507D03*
X607544Y33340D03*
X619382Y260089D03*
X615532Y259700D03*
X611706Y259387D03*
X606700Y255600D03*
X604074Y254394D03*
X609500Y254900D03*
X609937Y252106D03*
X615537Y264789D03*
X619100Y265300D03*
X611536Y264385D03*
X609896Y272889D03*
X608996Y270206D03*
X605100Y270100D03*
X605065Y272967D03*
X623532Y20007D03*
X623555Y25107D03*
X619607Y19807D03*
X627255Y25107D03*
X627231Y19907D03*
X630955Y25207D03*
X631000Y20107D03*
X634555Y25307D03*
X634757Y20207D03*
X619730Y24864D03*
X630432Y260100D03*
X626682Y260300D03*
X622933Y260189D03*
X634207Y260300D03*
X630455Y265400D03*
X634280Y265332D03*
X626651Y265489D03*
X622899Y265189D03*
X644193Y12907D03*
X648800Y12707D03*
X638400Y20607D03*
X638290Y25674D03*
X642246Y25807D03*
X642451Y20707D03*
X645300Y15507D03*
X648400Y15490D03*
X647000Y29607D03*
X649550Y30807D03*
X643700Y33290D03*
X644100Y30307D03*
X638032Y260342D03*
X642802Y252186D03*
X645920Y254130D03*
X635043Y252106D03*
X638900Y254809D03*
X643020Y254710D03*
X647800Y252300D03*
X638090Y265340D03*
X642937Y273089D03*
X646360Y271530D03*
X637288Y270100D03*
X637337Y272944D03*
X648948Y262489D03*
X644090Y270420D03*
X648200Y265300D03*
X644550Y267170D03*
X648291Y273140D03*
X662359Y12379D03*
X659400Y25907D03*
Y20474D03*
X662192Y14874D03*
X663202Y25973D03*
X655602Y25223D03*
X663200Y20956D03*
X655700Y20225D03*
X662503Y33207D03*
X657900Y30690D03*
X664678Y30307D03*
X661708Y30699D03*
X659437Y246389D03*
X665500Y252189D03*
X653600Y252130D03*
X659500Y274000D03*
X665100Y272700D03*
X652233Y262489D03*
X653000Y264900D03*
X653041Y272989D03*
X671290Y12457D03*
X665901Y12307D03*
X674320Y14219D03*
X666175Y14807D03*
X680580Y22807D03*
X677295D03*
X674400Y31307D03*
X671295Y33190D03*
X671900Y30707D03*
X675970Y33267D03*
X670200Y254700D03*
X673770Y254752D03*
X669700Y270900D03*
X672800Y272700D03*
X676113Y262489D03*
X679398D03*
X690102Y12502D03*
X684760Y12256D03*
X692200Y15357D03*
X682013Y14848D03*
X695029Y22853D03*
X693300Y30607D03*
X689624Y30383D03*
X685700Y30807D03*
X681900Y30907D03*
X682800Y254900D03*
X685382Y252200D03*
X688800Y254600D03*
X692250Y255700D03*
X682481Y270700D03*
X685100Y273100D03*
X689700Y270800D03*
X692537Y272989D03*
X696192Y262489D03*
X709000Y12407D03*
X702000Y12607D03*
X705031Y14515D03*
X698277Y22855D03*
X708900Y30407D03*
X704430Y33313D03*
X701800Y30807D03*
X701649Y255049D03*
X704178Y252189D03*
X707800Y255000D03*
X711400Y255072D03*
X701300Y270777D03*
X704277Y272989D03*
X709400Y272600D03*
X699477Y262489D03*
X723586Y14080D03*
X712182Y14124D03*
X720100Y14707D03*
X718375Y22907D03*
X715090D03*
X727000Y30407D03*
X723500Y29907D03*
X721747Y32954D03*
X712400Y30807D03*
X721500Y255000D03*
X724374Y254515D03*
X712200Y270500D03*
X722400Y270800D03*
X725300Y272800D03*
X717452Y262489D03*
X720737D03*
X715900Y270000D03*
X742200Y12407D03*
X728010Y12857D03*
X739000Y14407D03*
X731169Y14584D03*
X736091Y23607D03*
X732806D03*
X742100Y33007D03*
X740200Y29907D03*
X730500D03*
X730400Y255400D03*
X732200Y252200D03*
X741560Y255000D03*
X730400Y272850D03*
X732740Y270200D03*
X741200Y270500D03*
X735168Y262489D03*
X738453D03*
X744900Y20500D03*
X745000Y23000D03*
X747441Y33007D03*
X744437Y252189D03*
X744200Y272600D03*
X753000Y272100D03*
G54D17*
X42717Y191732D03*
G54D19*
X144000Y67875D03*
Y147125D03*
X276811Y263386D03*
X296811D03*
X457913Y45276D03*
X477913D03*
G54D14*
X13000Y137000D03*
Y141500D03*
X13100Y150600D03*
X13000Y146000D03*
X45500Y118000D03*
X76200Y187200D03*
X86500Y177500D03*
X90700Y177050D03*
X122250Y228750D03*
Y233000D03*
Y237300D03*
Y241500D03*
X133941Y208863D03*
X131003Y205766D03*
X138100Y208100D03*
X136500Y272500D03*
X158700Y213800D03*
X309100Y206800D03*
X315400Y110800D03*
X311600D03*
X322691Y136023D03*
X323550Y142104D03*
X319401Y149354D03*
X317698Y152311D03*
X315384Y166733D03*
X324953Y161722D03*
X323165Y171937D03*
X324436Y175705D03*
X326399Y169401D03*
X319942Y180524D03*
X320029Y184300D03*
X318700Y207800D03*
X311600Y207600D03*
X328000Y97100D03*
X334850Y96900D03*
X335500Y91600D03*
X339500Y102000D03*
X332600Y101400D03*
X333551Y115090D03*
X333416Y108899D03*
X341309Y135651D03*
X329693Y134428D03*
X331290Y125810D03*
X330870Y130540D03*
X336190Y141970D03*
X330796Y146221D03*
X333742Y161624D03*
X332185Y153806D03*
X334470Y164760D03*
X335400Y169600D03*
X333842Y177224D03*
X332300Y173900D03*
X339875Y177303D03*
X334715Y180900D03*
X329028Y199931D03*
X344523Y98477D03*
X344500Y94000D03*
X347230Y100190D03*
X355175Y108212D03*
X348076Y108910D03*
X354333Y125665D03*
X343000Y124000D03*
X342880Y146180D03*
X350800Y138300D03*
X355342Y143424D03*
X348743Y149100D03*
X342716Y161593D03*
X345562Y178700D03*
X349751Y187241D03*
X356800Y191000D03*
X361141Y104099D03*
X369997Y113706D03*
X358000Y115500D03*
X364600Y137063D03*
X367221Y125428D03*
X370000Y122563D03*
X367121Y128628D03*
X362111Y130128D03*
X361726Y140268D03*
X361700Y146549D03*
X361400Y187600D03*
X368455Y196455D03*
X371299Y196008D03*
X361300Y184500D03*
X369009Y186191D03*
X359750Y208390D03*
X359910Y214100D03*
X371100Y199500D03*
X365250Y208600D03*
X369580Y215400D03*
X377818Y115008D03*
X377800Y124163D03*
X384650Y183170D03*
X376742Y181524D03*
X376800Y193500D03*
X376900Y196600D03*
X380510Y185500D03*
X384684Y191950D03*
X376300Y213700D03*
X382471Y199843D03*
X385900Y222600D03*
X382700Y226000D03*
X379700Y216500D03*
X372950Y217400D03*
X393653Y121122D03*
X401500Y122600D03*
X401256Y128755D03*
X397800Y130000D03*
X395573Y175400D03*
X400352Y180171D03*
X402962Y189014D03*
X397728Y189053D03*
X389200Y227400D03*
X409110Y120910D03*
X412100Y135600D03*
X412600Y124100D03*
X417753Y131322D03*
X404400Y128900D03*
X415700Y143100D03*
X410302Y141864D03*
X406042Y147025D03*
X415100Y149800D03*
X407399Y142561D03*
X408837Y149809D03*
X413314Y154908D03*
X416315Y183219D03*
X412000Y187500D03*
X405102Y187874D03*
X422300Y126300D03*
X432542Y136898D03*
X426982Y131334D03*
X423496Y144000D03*
X428363Y141756D03*
X426000Y167370D03*
X430542Y160753D03*
X430600Y164513D03*
X422363Y154700D03*
X423966Y190846D03*
X423800Y196500D03*
X433842Y197021D03*
X421848Y186550D03*
X426311Y204399D03*
X443443Y144757D03*
X437398Y146257D03*
X435004Y142110D03*
G54D23*
X305900Y121151D03*
X311200Y114800D03*
X311410Y118110D03*
X312000Y122600D03*
X312917Y133440D03*
X312829Y181940D03*
X345837Y199887D03*
G54D12*
X14000Y104500D03*
X14400Y98000D03*
X14000Y109500D03*
X14500Y198000D03*
X17301Y212401D03*
X4500Y228900D03*
X4600Y223100D03*
X17300Y218307D03*
X10000Y229500D03*
X16400Y224212D03*
X4500Y234800D03*
X4400Y245100D03*
X16118Y230118D03*
X10194Y243106D03*
X9500Y234200D03*
X16899Y241929D03*
X16300Y236023D03*
X4400Y256700D03*
X10190Y258510D03*
X10194Y254917D03*
X10190Y246699D03*
X16899Y247834D03*
Y253740D03*
Y259645D03*
X5000Y275000D03*
X12600Y266900D03*
X7600Y268100D03*
X16899Y265551D03*
X15300Y285800D03*
X4900Y285700D03*
X23400Y81550D03*
X25000Y77300D03*
X32800Y120400D03*
X25800Y120300D03*
X29200D03*
X30000Y196200D03*
X21900Y205400D03*
X31500Y207500D03*
X25200Y286000D03*
X40500Y127700D03*
X38500Y148000D03*
X48500D03*
X41000Y152300D03*
Y143300D03*
X46000D03*
Y152300D03*
X43500Y148000D03*
Y138500D03*
X48500D03*
X38500D03*
X45800Y158100D03*
X34800Y198800D03*
Y203700D03*
X37600Y212700D03*
Y207800D03*
X34500Y216000D03*
X40400Y217100D03*
X40700Y224000D03*
X40200Y238300D03*
Y231300D03*
Y245300D03*
X40500Y260000D03*
X40600Y252500D03*
X52500Y96500D03*
Y106500D03*
X57500Y96500D03*
X60000Y101500D03*
X50000D03*
X55000D03*
X57500Y106500D03*
X60000Y111300D03*
X50000D03*
X55000D03*
X50500Y160000D03*
X54700Y192200D03*
X52700Y184800D03*
X62800Y184300D03*
X57600Y214200D03*
X74000Y37642D03*
X66500D03*
X78300Y64300D03*
X72137Y210237D03*
X79500Y230000D03*
X78700Y259800D03*
X67600Y255800D03*
X66300Y259300D03*
X67000Y263200D03*
X82211Y37747D03*
X89862Y37849D03*
X89400Y58200D03*
X83600Y57600D03*
X95500Y93500D03*
X94000Y137500D03*
Y133000D03*
X84500Y230000D03*
X89500D03*
X84500Y225000D03*
Y235000D03*
X91400Y270300D03*
X98500Y37642D03*
X105794Y37692D03*
X104400Y57700D03*
X96800Y53300D03*
X99500Y91500D03*
Y96000D03*
X104000Y92000D03*
Y96500D03*
X105775Y137349D03*
X103175Y134050D03*
X98500Y137500D03*
X109000Y134050D03*
X98500Y133000D03*
X95700Y197200D03*
X99600Y225700D03*
X99328Y235370D03*
X109000Y231400D03*
X113605Y37665D03*
X121500Y37642D03*
X121400Y60100D03*
X114800Y60700D03*
X114500Y134050D03*
X120500Y139000D03*
X125000Y178000D03*
X119760Y191419D03*
X115760D03*
X123760D03*
X129336Y37652D03*
X137300Y37642D03*
X136400Y60600D03*
X130400D03*
X136500Y101523D03*
X136770Y113000D03*
X136500Y126300D03*
X132700Y158600D03*
X153088Y37653D03*
X145070Y37642D03*
X143700Y54503D03*
X154615Y54500D03*
X152811Y84300D03*
X157175Y115462D03*
X150670Y112100D03*
Y122300D03*
X150500Y183000D03*
X157000Y169194D03*
X168791Y37689D03*
X160898Y37704D03*
X169600Y53000D03*
X159957Y51932D03*
X167500Y68000D03*
X158105Y96775D03*
X171800Y126600D03*
X162900Y152200D03*
X167602Y160684D03*
X169800Y181448D03*
X165700Y203400D03*
X162000Y226000D03*
X167000D03*
Y221500D03*
X162000D03*
Y230500D03*
X167000D03*
X162000Y235000D03*
X176640Y37699D03*
X184500Y37700D03*
X185000Y51600D03*
X175758Y52879D03*
X184300Y78500D03*
X177200Y130575D03*
X187597Y133697D03*
X176400Y175700D03*
X185546Y192509D03*
X180546D03*
X175546D03*
X177500Y209500D03*
X176800Y241600D03*
X186500Y276500D03*
Y281000D03*
X192400Y37642D03*
X200300D03*
X191700Y52100D03*
X201500Y54500D03*
X196900Y68700D03*
X198500Y83800D03*
X193485Y83724D03*
X202500Y97000D03*
X188363Y116137D03*
X201252Y137766D03*
X192237Y147300D03*
X199900Y154200D03*
X200900Y177000D03*
X202800Y191400D03*
X196000Y186897D03*
X191400Y206100D03*
X203100Y252900D03*
X191100Y276600D03*
X190900Y280800D03*
X207600Y37642D03*
X216085Y37649D03*
X210900Y57600D03*
X213558Y98500D03*
X205689Y112879D03*
X205850Y118175D03*
X210100Y135800D03*
X213850Y179850D03*
X205920Y221550D03*
X211900Y253000D03*
X207500D03*
X212400Y281200D03*
X217000Y281000D03*
X212500Y277000D03*
X208000D03*
X223868Y37686D03*
X231780Y37691D03*
X229036Y83000D03*
X231562Y143827D03*
X231611Y138336D03*
X226452Y147300D03*
X233350Y180700D03*
X232225Y193275D03*
X233500Y258958D03*
X228000Y259000D03*
X239599Y37673D03*
X247500Y37642D03*
X238800Y45300D03*
X240200Y59275D03*
X247500Y60000D03*
X244463Y130655D03*
X242950Y155800D03*
X236477Y179357D03*
X239300Y196800D03*
X236861Y184967D03*
X248300Y213500D03*
X248000Y259000D03*
X238500D03*
X243000D03*
X261900Y44900D03*
X255000Y37642D03*
X263100Y37700D03*
X264700Y59400D03*
X256200Y59200D03*
X264189Y98252D03*
X257000Y213500D03*
X252700D03*
X252500Y259000D03*
X271000Y37800D03*
X278800Y37700D03*
X274000Y55800D03*
X268928Y112625D03*
X268895Y107350D03*
X268300Y141869D03*
X269772Y188274D03*
X274700Y222100D03*
X286900Y37800D03*
X294500Y37900D03*
X292500Y60500D03*
X284000Y55800D03*
X288700Y71100D03*
X292100D03*
X295300Y66200D03*
X285100Y129510D03*
X281500Y142100D03*
X295900Y154200D03*
X287700Y211900D03*
X295300Y238100D03*
X285000Y261700D03*
X310348Y37900D03*
X302600Y37800D03*
X302400Y59500D03*
X306100Y90600D03*
X311000Y141731D03*
X297250Y163700D03*
X311242Y158732D03*
X305290Y187836D03*
X301320Y191060D03*
X310500Y195600D03*
X308200D03*
X326096Y37900D03*
X318048Y37700D03*
X311598Y57522D03*
X322548Y58300D03*
X323882Y71643D03*
X318882D03*
X321300Y88200D03*
X325350Y114500D03*
X326313Y122380D03*
X311460Y172078D03*
X323800Y192150D03*
X323789Y188117D03*
X326500Y187900D03*
X311900Y188070D03*
X319500Y212100D03*
X315585Y207787D03*
X324100Y208000D03*
X325200Y221700D03*
X319400Y216200D03*
X313600Y237700D03*
X321400D03*
X322000Y264300D03*
X333700Y38000D03*
X328300Y58200D03*
X337000Y74202D03*
X328882Y71643D03*
X330470Y112515D03*
X330910Y115010D03*
X338421Y153802D03*
X326831Y196119D03*
X337670Y213520D03*
X332974Y210874D03*
X339800Y207400D03*
X330200Y216800D03*
X336000Y219750D03*
X333036Y231910D03*
X327100Y237100D03*
X353100Y56151D03*
X346600Y121100D03*
X355460Y149510D03*
X355413Y156050D03*
X351700Y167300D03*
X355300Y174600D03*
X350000Y177700D03*
X353321Y180128D03*
X350409Y199755D03*
X354700Y199900D03*
X363583Y37642D03*
X368721Y108528D03*
X365721Y115528D03*
X366400Y112200D03*
X371176Y136890D03*
X364700Y152713D03*
X368100Y162200D03*
X358342Y165324D03*
X358576Y162090D03*
X368000Y168500D03*
X361292Y181409D03*
X365800Y264900D03*
X362400D03*
X369300D03*
X375400Y37700D03*
X374200Y143294D03*
X387000Y155850D03*
X380500Y168500D03*
X383548Y168390D03*
X376800Y178600D03*
X380000Y263461D03*
X383500D03*
X376500D03*
X393561Y127130D03*
X396148Y155790D03*
X393208D03*
X399298Y165240D03*
X395641Y188045D03*
X393000Y236200D03*
X397400Y239700D03*
X389500Y275300D03*
X416922Y116613D03*
X405990Y144251D03*
X409096Y143963D03*
X410100Y157700D03*
X408900Y162463D03*
X410408Y170261D03*
X405100Y178500D03*
X407552Y170424D03*
X405700Y246500D03*
X430500Y17000D03*
X427500Y112091D03*
X425200Y118823D03*
X430342Y119724D03*
X426900Y160040D03*
X419340Y170500D03*
X434482Y177021D03*
X428400Y185900D03*
X423900Y257500D03*
X444783Y28451D03*
X439276Y159645D03*
X443800Y246100D03*
X445300Y274400D03*
X451000Y257413D03*
X456300Y275300D03*
X474000Y9000D03*
X467200Y4400D03*
X480400Y154050D03*
X467100Y154200D03*
X477000Y154050D03*
X470100Y154200D03*
X473500Y154050D03*
X467700Y245500D03*
X481500Y8900D03*
X489600Y8800D03*
X483800Y154050D03*
X487200Y154100D03*
X497100Y8800D03*
X506800Y12907D03*
X508700Y17207D03*
X506500Y32807D03*
X514360Y12417D03*
X526000Y12507D03*
X519426Y12318D03*
X522311Y16720D03*
X514300Y20507D03*
X519623Y20457D03*
X522700Y30007D03*
X513005Y32412D03*
X519400Y33340D03*
X526700Y33207D03*
X524700Y119500D03*
X515000Y119270D03*
X524700Y145041D03*
X537964Y12317D03*
X532500Y13407D03*
X541114Y12307D03*
X528219Y15096D03*
X532472Y20515D03*
X537410Y20584D03*
X529000Y30007D03*
X541950Y33340D03*
X532542Y33307D03*
X537200Y33207D03*
X531000Y228350D03*
X547500Y12507D03*
X553720Y12297D03*
X550234Y14997D03*
X553797Y20496D03*
X549500Y29107D03*
X553250Y33207D03*
X547306Y33134D03*
X552100Y136000D03*
X557100D03*
X558448Y12407D03*
X566040Y12317D03*
X566000Y16507D03*
X572200Y28707D03*
X558500Y20507D03*
X573200Y19907D03*
X565470Y33287D03*
X573242Y32462D03*
X560635Y33264D03*
X572100Y136000D03*
X567100D03*
X562000Y127800D03*
X562100Y136000D03*
X562000Y144900D03*
X573470Y12347D03*
X578620Y12357D03*
X585280Y12267D03*
X578600Y20307D03*
X590000Y14007D03*
X594500Y4007D03*
X599300Y119270D03*
X588800Y145000D03*
X599200D03*
X598814Y240095D03*
X614700Y14107D03*
X615951Y22356D03*
X615044Y33190D03*
X618877Y30790D03*
X617700Y125500D03*
X615100Y238900D03*
X633500Y12406D03*
X624000D03*
X634757Y22707D03*
X623480Y22564D03*
X631007Y22707D03*
X619700Y22307D03*
X627257Y22407D03*
X624100Y33190D03*
X633449D03*
X623900Y239600D03*
X641745Y12367D03*
X645200Y27707D03*
X646800Y17607D03*
X642257Y23307D03*
X638507Y23183D03*
X650200Y33307D03*
X641900Y31507D03*
X646000Y46007D03*
X640000D03*
X639500Y136490D03*
X648500Y162600D03*
X657897Y12504D03*
X651316Y12360D03*
X664212Y16356D03*
X663300Y23454D03*
X662916Y28457D03*
X655592Y22723D03*
X659400Y23207D03*
X657900Y33190D03*
X654500Y46107D03*
X653000Y93000D03*
X650726Y125724D03*
X664212Y147993D03*
X661600Y156700D03*
X654100Y221800D03*
X659811Y260757D03*
X657500Y258400D03*
X661308Y263698D03*
X655500Y270500D03*
X657787Y264179D03*
X656000Y261400D03*
X655523Y266616D03*
X658667Y267622D03*
X675990Y12357D03*
X669600Y17907D03*
X676600Y20307D03*
X671500Y15007D03*
X678400Y114500D03*
X668411Y148089D03*
X678500Y141500D03*
X667061Y175239D03*
X676200Y181600D03*
X687602Y12439D03*
X694200Y13507D03*
X681280Y12457D03*
X684500Y15507D03*
X689595Y27883D03*
X685400Y28307D03*
X681700Y20507D03*
X694205Y20302D03*
X693700Y33107D03*
X681280Y33340D03*
X687900Y33327D03*
X693500Y148000D03*
X690000Y159000D03*
X694500D03*
X684700Y179800D03*
X694600Y229800D03*
X699503Y12482D03*
X706360Y12397D03*
X705604Y16949D03*
X710813Y28796D03*
X699104Y20495D03*
X707157Y33333D03*
X700940Y33340D03*
X700089Y91411D03*
X701600Y104900D03*
X701400Y98400D03*
X698000Y181500D03*
X704700Y183800D03*
X710200Y201700D03*
X714000Y12407D03*
X719110Y12347D03*
X725530Y12507D03*
X714100Y20607D03*
X719220Y20553D03*
X721074Y30514D03*
X718350Y33107D03*
X712450Y33340D03*
X725653Y32654D03*
X725632Y49600D03*
X721950Y51950D03*
X722000Y74500D03*
X717000D03*
X715000Y80300D03*
X714500Y85500D03*
X715700Y124200D03*
X727187Y140000D03*
X717000Y187500D03*
X715500Y205837D03*
X737300Y12307D03*
X732110Y12267D03*
X728500Y15507D03*
X742100Y28107D03*
X732000Y20307D03*
X736748D03*
X728500Y27907D03*
X733474Y33340D03*
X738487Y33094D03*
X739500Y75500D03*
X738000Y65700D03*
X738500Y90000D03*
X731340Y82515D03*
X739500Y114900D03*
X741104Y133763D03*
X736900Y162300D03*
X729500D03*
X733400D03*
X737000Y188315D03*
X734000Y205000D03*
X745100Y12256D03*
X744800Y33007D03*
X752500Y49007D03*
X756000Y106000D03*
X758176Y135024D03*
X745104Y129763D03*
X749104Y133763D03*
X745104D03*
X752191Y146613D03*
X745104Y137763D03*
X747000Y162000D03*
X750500D03*
X746000Y182300D03*
X764500Y84800D03*
X760400Y88700D03*
X768100Y89000D03*
X761300Y95700D03*
X768500Y114000D03*
X763600Y168000D03*
X764000Y188000D03*
Y197500D03*
Y192810D03*
Y202310D03*
X769500Y234500D03*
X769400Y252700D03*
X785500Y8000D03*
X784000Y31000D03*
X781500Y51000D03*
X777000Y93100D03*
X774300Y102500D03*
X778500D03*
Y107000D03*
X774300D03*
X783000Y113000D03*
Y118500D03*
Y123000D03*
X779000Y142000D03*
X788515Y144060D03*
X784515D03*
X796515D03*
X792515D03*
X800515D03*
Y148060D03*
X796515D03*
X792515D03*
X810500Y196500D03*
Y192300D03*
X809200Y209500D03*
Y213700D03*
Y218400D03*
X809100Y228600D03*
Y224400D03*
X808700Y238300D03*
Y234100D03*
Y242900D03*
X809500Y251500D03*
Y257000D03*
X808700Y247100D03*
X809700Y285900D03*
X820500Y6500D03*
X821900Y273100D03*
X821600Y285500D03*
G54D31*
X804032Y27032D03*
Y67032D03*
G54D29*
X350197Y231103D03*
G54D11*
X11500Y68500D03*
X12000Y279000D03*
X816000Y280000D03*
G54D16*
X45669Y77185D03*
Y172460D03*
G54D21*
X200197Y282677D03*
X298622D03*
G54D10*
X-19686Y15748D03*
Y573228D03*
X846455Y15748D03*
Y573228D03*
G54D25*
X315613Y100850D03*
X339280Y127380D03*
X431188Y116105D03*
X434700Y131800D03*
G54D26*
X325300Y112300D03*
X319252Y140949D03*
X324200Y157800D03*
X311417Y153821D03*
X341300Y169600D03*
X332100Y185600D03*
X338000Y185700D03*
X335000Y185500D03*
X332800Y187700D03*
X358500Y137000D03*
X385750Y128517D03*
X380400Y133928D03*
X387000Y143280D03*
X380398Y143418D03*
X383395Y143306D03*
X399452Y133964D03*
X389380Y130100D03*
X389721Y143320D03*
X393000Y140268D03*
X403132Y144374D03*
X431620Y154620D03*
X421697Y174049D03*
X439275Y124197D03*
X456200Y129600D03*
X459700Y133600D03*
X459800Y126200D03*
X456500Y123000D03*
X457700Y167400D03*
X456500Y174900D03*
X454500Y171100D03*
G54D27*
X322010Y118573D03*
X323007Y127672D03*
X338048Y196250D03*
X342029Y196427D03*
X349600Y126700D03*
X342760Y187810D03*
X371900Y89000D03*
X368600Y94100D03*
X365000Y94700D03*
X357721Y95100D03*
X360900Y94200D03*
X359942Y110924D03*
X375800Y87000D03*
X383450Y86900D03*
X387200D03*
X379500D03*
X379526Y106396D03*
X381950Y100950D03*
X381550Y117400D03*
X377800Y112063D03*
X377713Y121061D03*
X386777Y162155D03*
X377500Y156000D03*
X399300Y168400D03*
X393077Y168455D03*
X392596Y187541D03*
X417785Y162622D03*
X406000Y162663D03*
X412500Y194900D03*
X418800Y196700D03*
X416139Y192007D03*
X426800Y97850D03*
X419499Y139064D03*
X423910Y175700D03*
X432712Y172469D03*
X435453Y167560D03*
X507817Y252248D03*
X511200Y258900D03*
X509244Y272796D03*
X516600Y252200D03*
X521800Y252875D03*
X513776Y258563D03*
X516727Y273122D03*
X521790Y273140D03*
X517100Y265100D03*
X521987D03*
X532900Y255300D03*
X535098Y252600D03*
X527400Y252100D03*
X529300Y271000D03*
X528330Y273140D03*
X539937Y272989D03*
X539505Y265100D03*
X534905Y273097D03*
X534700Y265100D03*
X546200Y271000D03*
X546900Y273100D03*
X554434Y272914D03*
X603187Y252056D03*
X589500Y257100D03*
X589900Y268133D03*
X602450Y272900D03*
X598418Y262699D03*
X590322Y262361D03*
X594559Y262559D03*
X595386Y272932D03*
X608700Y257300D03*
X611845Y253723D03*
X611593Y261885D03*
X606200Y267800D03*
X615430Y262213D03*
X612393Y273026D03*
X619180Y262689D03*
X629937Y272990D03*
X630457Y262832D03*
X626680Y262989D03*
X634280Y262832D03*
X620437Y272990D03*
X622930Y262689D03*
X635197Y254602D03*
X638893Y252206D03*
X637987Y262842D03*
X639500Y268800D03*
X665300Y254700D03*
X661200Y248500D03*
X664500Y270000D03*
X661600Y272300D03*
X669930Y252150D03*
X674636Y252406D03*
X680600Y265000D03*
X675400D03*
X668000Y272890D03*
X680400Y273100D03*
X675400D03*
X690000Y256800D03*
X685390Y254900D03*
X688720Y252090D03*
X693860Y252210D03*
X681900Y252500D03*
X691900Y269300D03*
X683100Y268000D03*
X695500Y265000D03*
Y273100D03*
X687682Y272889D03*
X704137Y254796D03*
X699800Y252230D03*
X701704Y257549D03*
X707490Y252310D03*
X706000Y270500D03*
X700200Y264900D03*
X700300Y273100D03*
X706900Y273000D03*
X712350Y252640D03*
X725950Y252573D03*
X721395Y252175D03*
X721600Y257500D03*
X716737Y252189D03*
X716795Y265000D03*
X721400D03*
X721395Y273100D03*
X713100Y273000D03*
X716737Y272989D03*
X730300Y257900D03*
X734937Y253100D03*
X739750Y252800D03*
X729860Y269810D03*
X734200Y265100D03*
X739111Y264962D03*
X739838Y272813D03*
X727800Y272800D03*
X734510Y273110D03*
X744100Y254800D03*
X749000Y252200D03*
X746737Y272889D03*
G54D28*
X320321Y130528D03*
X351342Y114158D03*
X351000Y111700D03*
X351950Y214800D03*
X346500Y208350D03*
X345500Y213000D03*
X353792Y208466D03*
X355860Y216690D03*
X345300Y216700D03*
X359222Y197700D03*
G54D30*
X384810Y208530D03*
X384644Y205994D03*
%LPC*%
G75*
G54D32*
G01X10636Y-27865D02*
G02I-12000J0D01*
G01X14636D02*
X-17364D01*
G01X5486D02*
G02I-6850J0D01*
G01X-1364Y-43865D02*
Y-11865D01*
G01X14636Y-43865D02*
Y-123865D01*
G01D02*
X1309236D01*
G01X14636Y-79365D02*
X1309236D01*
G01X14636Y-43865D02*
X1309236D01*
G01X521736D02*
Y-123865D01*
G01X659236Y-43865D02*
Y-123865D01*
G01X774236Y-43865D02*
Y-123865D01*
G01X941736Y-43865D02*
Y-123865D01*
G01X1111736Y-43865D02*
Y-123865D01*
G01X1309236Y-43865D02*
Y-123865D01*
G01X1341236Y-27865D02*
X1309236D01*
G01X1337236D02*
G02I-12000J0D01*
G01X1332086D02*
G02I-6850J0D01*
G01X1325236Y-43865D02*
Y-11865D01*
G54D33*
G01X70851Y-113865D02*
Y-96365D01*
G01X80021D02*
Y-113865D01*
G01Y-105115D02*
X70851D01*
G01X92936Y-113865D02*
X91626Y-113573D01*
X90316Y-112407D01*
X89442Y-110365D01*
X89006Y-108032D01*
X89442Y-105698D01*
X90316Y-103657D01*
X91626Y-102490D01*
X92936Y-102199D01*
X94246Y-102490D01*
X95556Y-103657D01*
X96429Y-105698D01*
X96648Y-108032D01*
X96429Y-110365D01*
X95556Y-112407D01*
X94246Y-113573D01*
X92936Y-113865D01*
G01X106724D02*
Y-102199D01*
G01Y-105115D02*
X107598Y-103657D01*
X108908Y-102490D01*
X110654Y-102199D01*
X112182Y-102490D01*
X113493Y-103657D01*
X114148Y-105698D01*
Y-113865D01*
G01X124661Y-105990D02*
X131648D01*
X130993Y-103948D01*
X129901Y-102782D01*
X128373Y-102199D01*
X126844Y-102490D01*
X125534Y-103365D01*
X124661Y-105407D01*
X124224Y-107157D01*
Y-108907D01*
X124661Y-110657D01*
X125753Y-112407D01*
X127063Y-113573D01*
X128591Y-113865D01*
X130119Y-113282D01*
X131648Y-111532D01*
G01X140851Y-119115D02*
X142161Y-119698D01*
X143908Y-119115D01*
X144999Y-117949D01*
X145873Y-116490D01*
X147182Y-111824D01*
X150021Y-102199D01*
G01X143034D02*
X147182Y-111824D01*
G01X182182Y-104532D02*
X183056Y-103657D01*
X183711Y-102199D01*
X184148Y-100156D01*
X183711Y-98407D01*
X182838Y-97240D01*
X181309Y-96365D01*
X175414D01*
Y-113865D01*
X182619D01*
X184148Y-112699D01*
X185021Y-110948D01*
X185458Y-108907D01*
X185021Y-106865D01*
X183711Y-105115D01*
X182182Y-104532D01*
X175414D01*
G01X201866Y-113865D02*
Y-102199D01*
G01Y-104240D02*
X200993Y-103074D01*
X199682Y-102490D01*
X198154Y-102199D01*
X196626Y-102782D01*
X195316Y-103948D01*
X194442Y-105698D01*
X194006Y-108032D01*
X194442Y-110365D01*
X195316Y-112115D01*
X196626Y-113282D01*
X198154Y-113865D01*
X199682Y-113573D01*
X200993Y-112699D01*
X201866Y-111532D01*
G01X219366Y-96365D02*
Y-113865D01*
G01Y-111241D02*
X218493Y-112699D01*
X217182Y-113573D01*
X215654Y-113865D01*
X213908Y-113282D01*
X212598Y-111824D01*
X211724Y-110074D01*
X211506Y-108032D01*
X211724Y-105990D01*
X212598Y-104240D01*
X213908Y-102782D01*
X215654Y-102199D01*
X217182Y-102490D01*
X218274Y-103074D01*
X219366Y-104240D01*
G01X229879Y-118240D02*
X231408Y-119407D01*
X233154Y-119698D01*
X234682Y-119407D01*
X235993Y-117949D01*
X236866Y-115907D01*
Y-102199D01*
G01Y-104532D02*
X235993Y-103365D01*
X234682Y-102490D01*
X233154Y-102199D01*
X231408Y-102782D01*
X230316Y-103948D01*
X229442Y-105990D01*
X229006Y-108032D01*
X229224Y-109782D01*
X230098Y-111824D01*
X231408Y-113282D01*
X233154Y-113865D01*
X234464Y-113573D01*
X235993Y-112407D01*
X236866Y-111241D01*
G01X247161Y-105990D02*
X254148D01*
X253493Y-103948D01*
X252401Y-102782D01*
X250873Y-102199D01*
X249344Y-102490D01*
X248034Y-103365D01*
X247161Y-105407D01*
X246724Y-107157D01*
Y-108907D01*
X247161Y-110657D01*
X248253Y-112407D01*
X249563Y-113573D01*
X251091Y-113865D01*
X252619Y-113282D01*
X254148Y-111532D01*
G01X264879Y-113865D02*
Y-102199D01*
G01Y-104532D02*
X265971Y-103365D01*
X267063Y-102490D01*
X268591Y-102199D01*
X269682Y-102490D01*
X270993Y-103365D01*
G01X298569Y-113865D02*
Y-96365D01*
X303809D01*
X305556Y-97240D01*
X306866Y-99282D01*
X307303Y-101615D01*
X306866Y-103948D01*
X305774Y-105698D01*
X303809Y-106574D01*
X298569D01*
G01X324366Y-113865D02*
Y-102199D01*
G01Y-104240D02*
X323493Y-103074D01*
X322182Y-102490D01*
X320654Y-102199D01*
X319126Y-102782D01*
X317816Y-103948D01*
X316942Y-105698D01*
X316506Y-108032D01*
X316942Y-110365D01*
X317816Y-112115D01*
X319126Y-113282D01*
X320654Y-113865D01*
X322182Y-113573D01*
X323493Y-112699D01*
X324366Y-111532D01*
G01X334224Y-113865D02*
Y-102199D01*
G01Y-105115D02*
X335098Y-103657D01*
X336408Y-102490D01*
X338154Y-102199D01*
X339682Y-102490D01*
X340993Y-103657D01*
X341648Y-105698D01*
Y-113865D01*
G01X355436Y-96365D02*
Y-113865D01*
G01X352379Y-102199D02*
X358493D01*
G01X369224Y-113865D02*
Y-96365D01*
G01Y-104823D02*
X370316Y-103365D01*
X371408Y-102490D01*
X373154Y-102199D01*
X374464Y-102490D01*
X375993Y-103657D01*
X376648Y-105407D01*
Y-113865D01*
G01X387161Y-105990D02*
X394148D01*
X393493Y-103948D01*
X392401Y-102782D01*
X390873Y-102199D01*
X389344Y-102490D01*
X388034Y-103365D01*
X387161Y-105407D01*
X386724Y-107157D01*
Y-108907D01*
X387161Y-110657D01*
X388253Y-112407D01*
X389563Y-113573D01*
X391091Y-113865D01*
X392619Y-113282D01*
X394148Y-111532D01*
G01X404879Y-113865D02*
Y-102199D01*
G01Y-104532D02*
X405971Y-103365D01*
X407063Y-102490D01*
X408591Y-102199D01*
X409682Y-102490D01*
X410993Y-103365D01*
G01X437259Y-113865D02*
Y-96365D01*
X442936Y-110948D01*
X448613Y-96365D01*
Y-113865D01*
G01X462182Y-104532D02*
X463056Y-103657D01*
X463711Y-102199D01*
X464148Y-100156D01*
X463711Y-98407D01*
X462838Y-97240D01*
X461309Y-96365D01*
X455414D01*
Y-113865D01*
X462619D01*
X464148Y-112699D01*
X465021Y-110948D01*
X465458Y-108907D01*
X465021Y-106865D01*
X463711Y-105115D01*
X462182Y-104532D01*
X455414D01*
G01X227259Y-68865D02*
Y-51365D01*
X232936Y-65948D01*
X238613Y-51365D01*
Y-68865D01*
G01X250436D02*
X249126Y-68573D01*
X247816Y-67407D01*
X246942Y-65365D01*
X246506Y-63032D01*
X246942Y-60698D01*
X247816Y-58657D01*
X249126Y-57490D01*
X250436Y-57199D01*
X251746Y-57490D01*
X253056Y-58657D01*
X253929Y-60698D01*
X254148Y-63032D01*
X253929Y-65365D01*
X253056Y-67407D01*
X251746Y-68573D01*
X250436Y-68865D01*
G01X271866Y-51365D02*
Y-68865D01*
G01Y-66241D02*
X270993Y-67699D01*
X269682Y-68573D01*
X268154Y-68865D01*
X266408Y-68282D01*
X265098Y-66824D01*
X264224Y-65074D01*
X264006Y-63032D01*
X264224Y-60990D01*
X265098Y-59240D01*
X266408Y-57782D01*
X268154Y-57199D01*
X269682Y-57490D01*
X270774Y-58074D01*
X271866Y-59240D01*
G01X282161Y-60990D02*
X289148D01*
X288493Y-58948D01*
X287401Y-57782D01*
X285873Y-57199D01*
X284344Y-57490D01*
X283034Y-58365D01*
X282161Y-60407D01*
X281724Y-62157D01*
Y-63907D01*
X282161Y-65657D01*
X283253Y-67407D01*
X284563Y-68573D01*
X286091Y-68865D01*
X287619Y-68282D01*
X289148Y-66532D01*
G01X302936Y-68865D02*
Y-51365D01*
G01X542319Y-68865D02*
Y-51365D01*
X547559D01*
X549306Y-52240D01*
X550616Y-54282D01*
X551053Y-56615D01*
X550616Y-58948D01*
X549524Y-60698D01*
X547559Y-61574D01*
X542319D01*
G01X568989Y-52824D02*
X567679Y-51948D01*
X566151Y-51365D01*
X564404D01*
X562439Y-52240D01*
X560911Y-53698D01*
X559819Y-55449D01*
X558946Y-58365D01*
X558727Y-60990D01*
X559164Y-63615D01*
X559819Y-65365D01*
X561129Y-67115D01*
X562658Y-68282D01*
X564186Y-68865D01*
X565714D01*
X567243Y-68282D01*
X568553Y-67407D01*
X569645Y-66241D01*
G01X583432Y-59532D02*
X584306Y-58657D01*
X584961Y-57199D01*
X585398Y-55156D01*
X584961Y-53407D01*
X584088Y-52240D01*
X582559Y-51365D01*
X576664D01*
Y-68865D01*
X583869D01*
X585398Y-67699D01*
X586271Y-65948D01*
X586708Y-63907D01*
X586271Y-61865D01*
X584961Y-60115D01*
X583432Y-59532D01*
X576664D01*
G01X592636Y-74698D02*
X605736D01*
G01X611664Y-68865D02*
Y-51365D01*
X621708Y-68865D01*
Y-51365D01*
G01X634186Y-68865D02*
X632439Y-68573D01*
X630911Y-67407D01*
X629601Y-65657D01*
X628727Y-63615D01*
X628291Y-61282D01*
Y-58948D01*
X628727Y-56615D01*
X629601Y-54573D01*
X630911Y-52824D01*
X632439Y-51657D01*
X634186Y-51365D01*
X635932Y-51657D01*
X637461Y-52824D01*
X638771Y-54573D01*
X639645Y-56615D01*
X640081Y-58948D01*
Y-61282D01*
X639645Y-63615D01*
X638771Y-65657D01*
X637461Y-67407D01*
X635932Y-68573D01*
X634186Y-68865D01*
G01X555436Y-113865D02*
Y-96365D01*
X552816Y-99865D01*
G01Y-113865D02*
X558056D01*
G01X568133Y-110365D02*
X569442Y-112407D01*
X571189Y-113573D01*
X573154Y-113865D01*
X574901Y-113573D01*
X576648Y-112115D01*
X577739Y-110365D01*
X577958Y-108615D01*
X577521Y-106574D01*
X575993Y-105115D01*
X574464Y-104532D01*
X572499D01*
G01X574464D02*
X575774Y-103657D01*
X576866Y-102199D01*
X577303Y-100449D01*
X576866Y-98698D01*
X575774Y-97240D01*
X573809Y-96365D01*
X571844Y-96657D01*
X569879Y-97824D01*
G01X590436Y-113865D02*
Y-96365D01*
X587816Y-99865D01*
G01Y-113865D02*
X593056D01*
G01X603133Y-110365D02*
X604442Y-112407D01*
X606189Y-113573D01*
X608154Y-113865D01*
X609901Y-113573D01*
X611648Y-112115D01*
X612739Y-110365D01*
X612958Y-108615D01*
X612521Y-106574D01*
X610993Y-105115D01*
X609464Y-104532D01*
X607499D01*
G01X609464D02*
X610774Y-103657D01*
X611866Y-102199D01*
X612303Y-100449D01*
X611866Y-98698D01*
X610774Y-97240D01*
X608809Y-96365D01*
X606844Y-96657D01*
X604879Y-97824D01*
G01X625436Y-96365D02*
X623689Y-96948D01*
X622379Y-98407D01*
X621506Y-100156D01*
X620851Y-102490D01*
X620633Y-105115D01*
X620851Y-107740D01*
X621506Y-110074D01*
X622379Y-111824D01*
X623689Y-113282D01*
X625436Y-113865D01*
X627182Y-113282D01*
X628493Y-111824D01*
X629366Y-110074D01*
X630021Y-107740D01*
X630239Y-105115D01*
X630021Y-102490D01*
X629366Y-100156D01*
X628493Y-98407D01*
X627182Y-96948D01*
X625436Y-96365D01*
G01X685027Y-51365D02*
X690486Y-68865D01*
X695945Y-51365D01*
G01X712353Y-68865D02*
X703619D01*
Y-51365D01*
X712353D01*
G01X708859Y-59823D02*
X703619D01*
G01X721119Y-68865D02*
Y-51365D01*
X726578D01*
X728324Y-52240D01*
X729416Y-53407D01*
X729853Y-55740D01*
X729416Y-58074D01*
X728106Y-59532D01*
X726578Y-60407D01*
X721119D01*
G01X726578D02*
X729853Y-68865D01*
G01X742986Y-69448D02*
X742549Y-69157D01*
Y-68573D01*
X742986Y-68282D01*
X743423Y-68573D01*
Y-69157D01*
X742986Y-69448D01*
G01X707986Y-113865D02*
Y-96365D01*
X705366Y-99865D01*
G01Y-113865D02*
X710606D01*
G01X727232Y-104532D02*
X728106Y-103657D01*
X728761Y-102199D01*
X729198Y-100156D01*
X728761Y-98407D01*
X727888Y-97240D01*
X726359Y-96365D01*
X720464D01*
Y-113865D01*
X727669D01*
X729198Y-112699D01*
X730071Y-110948D01*
X730508Y-108907D01*
X730071Y-106865D01*
X728761Y-105115D01*
X727232Y-104532D01*
X720464D01*
G01X897303Y-96365D02*
Y-113865D01*
X888569D01*
G01X879148Y-111824D02*
X877619Y-113282D01*
X875873Y-113865D01*
X874126Y-113282D01*
X872598Y-111532D01*
X871506Y-108907D01*
X871069Y-106282D01*
Y-103074D01*
X871506Y-100449D01*
X872598Y-98115D01*
X873908Y-96948D01*
X875436Y-96365D01*
X877183Y-96948D01*
X878493Y-98115D01*
X879366Y-99865D01*
X879803Y-102199D01*
X879366Y-104240D01*
X878274Y-106282D01*
X876964Y-107449D01*
X875436Y-107740D01*
X873690Y-107157D01*
X872379Y-105698D01*
X871069Y-103074D01*
G01X856626Y-105115D02*
X852259D01*
Y-110365D01*
X853569Y-112115D01*
X855098Y-113282D01*
X857281Y-113865D01*
X859464Y-113282D01*
X860993Y-112115D01*
X862303Y-110365D01*
X863176Y-108323D01*
X863613Y-105990D01*
Y-103948D01*
X863176Y-102199D01*
X862303Y-100156D01*
X860993Y-98407D01*
X859683Y-97240D01*
X857936Y-96365D01*
X856408D01*
X854661Y-96948D01*
X853351Y-98115D01*
G01X845458Y-113865D02*
Y-96365D01*
X835414Y-113865D01*
Y-96365D01*
G01X827739Y-113865D02*
Y-96365D01*
X823373D01*
X821626Y-97240D01*
X820316Y-98407D01*
X819224Y-100156D01*
X818351Y-102199D01*
X818133Y-105115D01*
X818351Y-108032D01*
X819224Y-110074D01*
X820316Y-111824D01*
X821626Y-112990D01*
X823373Y-113865D01*
X827739D01*
G01X818569Y-51365D02*
Y-68865D01*
X827303D01*
G01X844366D02*
Y-57199D01*
G01Y-59240D02*
X843493Y-58074D01*
X842182Y-57490D01*
X840654Y-57199D01*
X839126Y-57782D01*
X837816Y-58948D01*
X836942Y-60698D01*
X836506Y-63032D01*
X836942Y-65365D01*
X837816Y-67115D01*
X839126Y-68282D01*
X840654Y-68865D01*
X842182Y-68573D01*
X843493Y-67699D01*
X844366Y-66532D01*
G01X853351Y-74115D02*
X854661Y-74698D01*
X856408Y-74115D01*
X857499Y-72949D01*
X858373Y-71490D01*
X859682Y-66824D01*
X862521Y-57199D01*
G01X855534D02*
X859682Y-66824D01*
G01X872161Y-60990D02*
X879148D01*
X878493Y-58948D01*
X877401Y-57782D01*
X875873Y-57199D01*
X874344Y-57490D01*
X873034Y-58365D01*
X872161Y-60407D01*
X871724Y-62157D01*
Y-63907D01*
X872161Y-65657D01*
X873253Y-67407D01*
X874563Y-68573D01*
X876091Y-68865D01*
X877619Y-68282D01*
X879148Y-66532D01*
G01X889879Y-68865D02*
Y-57199D01*
G01Y-59532D02*
X890971Y-58365D01*
X892063Y-57490D01*
X893591Y-57199D01*
X894682Y-57490D01*
X895993Y-58365D01*
G01X943619Y-110365D02*
X944711Y-112115D01*
X946021Y-113282D01*
X947549Y-113865D01*
X949296Y-113282D01*
X950606Y-112115D01*
X951916Y-110365D01*
X952353Y-108032D01*
Y-96365D01*
G01X965486Y-113865D02*
X963739Y-113573D01*
X962211Y-112407D01*
X960901Y-110657D01*
X960027Y-108615D01*
X959591Y-106282D01*
Y-103948D01*
X960027Y-101615D01*
X960901Y-99573D01*
X962211Y-97824D01*
X963739Y-96657D01*
X965486Y-96365D01*
X967232Y-96657D01*
X968761Y-97824D01*
X970071Y-99573D01*
X970945Y-101615D01*
X971381Y-103948D01*
Y-106282D01*
X970945Y-108615D01*
X970071Y-110657D01*
X968761Y-112407D01*
X967232Y-113573D01*
X965486Y-113865D01*
G01X978401Y-111532D02*
X980148Y-112990D01*
X982113Y-113865D01*
X983859D01*
X985606Y-112990D01*
X986916Y-111532D01*
X987571Y-109490D01*
X987134Y-107449D01*
X986043Y-105698D01*
X984078Y-104532D01*
X981458Y-103948D01*
X979929Y-102782D01*
X979274Y-100740D01*
X979711Y-98698D01*
X980803Y-97240D01*
X982331Y-96365D01*
X983859D01*
X985388Y-96948D01*
X986698Y-98407D01*
G01X1004853Y-113865D02*
X996119D01*
Y-96365D01*
X1004853D01*
G01X1001359Y-104823D02*
X996119D01*
G01X1013619Y-113865D02*
Y-96365D01*
X1018859D01*
X1020606Y-97240D01*
X1021916Y-99282D01*
X1022353Y-101615D01*
X1021916Y-103948D01*
X1020824Y-105698D01*
X1018859Y-106574D01*
X1013619D01*
G01X1030901Y-113865D02*
Y-96365D01*
G01X1040071D02*
Y-113865D01*
G01Y-105115D02*
X1030901D01*
G01X1066119Y-96365D02*
Y-113865D01*
X1074853D01*
G01X1082527D02*
X1087986Y-96365D01*
X1093445Y-113865D01*
G01X1091479Y-107740D02*
X1084492D01*
G01X1100683Y-96365D02*
Y-108907D01*
X1101556Y-111532D01*
X1103303Y-113282D01*
X1105486Y-113865D01*
X1107669Y-113282D01*
X1109416Y-111532D01*
X1110289Y-108907D01*
Y-96365D01*
G01X960683Y-68865D02*
Y-51365D01*
X965049D01*
X966796Y-52240D01*
X968106Y-53407D01*
X969198Y-55156D01*
X970071Y-57199D01*
X970289Y-60115D01*
X970071Y-63032D01*
X969198Y-65074D01*
X968106Y-66824D01*
X966796Y-67990D01*
X965049Y-68865D01*
X960683D01*
G01X979711Y-60990D02*
X986698D01*
X986043Y-58948D01*
X984951Y-57782D01*
X983423Y-57199D01*
X981894Y-57490D01*
X980584Y-58365D01*
X979711Y-60407D01*
X979274Y-62157D01*
Y-63907D01*
X979711Y-65657D01*
X980803Y-67407D01*
X982113Y-68573D01*
X983641Y-68865D01*
X985169Y-68282D01*
X986698Y-66532D01*
G01X997211Y-66824D02*
X998303Y-67990D01*
X999831Y-68865D01*
X1001141D01*
X1002451Y-68282D01*
X1003324Y-67407D01*
X1003761Y-66241D01*
X1003543Y-64490D01*
X1002669Y-63615D01*
X998739Y-61865D01*
X997866Y-59823D01*
X998303Y-58365D01*
X999176Y-57490D01*
X1000486Y-57199D01*
X1001796Y-57490D01*
X1003106Y-58365D01*
G01X1017986Y-57199D02*
Y-68865D01*
G01Y-52532D02*
X1017549Y-52240D01*
Y-51657D01*
X1017986Y-51365D01*
X1018423Y-51657D01*
Y-52240D01*
X1017986Y-52532D01*
G01X1032429Y-73240D02*
X1033958Y-74407D01*
X1035704Y-74698D01*
X1037232Y-74407D01*
X1038543Y-72949D01*
X1039416Y-70907D01*
Y-57199D01*
G01Y-59532D02*
X1038543Y-58365D01*
X1037232Y-57490D01*
X1035704Y-57199D01*
X1033958Y-57782D01*
X1032866Y-58948D01*
X1031992Y-60990D01*
X1031556Y-63032D01*
X1031774Y-64782D01*
X1032648Y-66824D01*
X1033958Y-68282D01*
X1035704Y-68865D01*
X1037014Y-68573D01*
X1038543Y-67407D01*
X1039416Y-66241D01*
G01X1049274Y-68865D02*
Y-57199D01*
G01Y-60115D02*
X1050148Y-58657D01*
X1051458Y-57490D01*
X1053204Y-57199D01*
X1054732Y-57490D01*
X1056043Y-58657D01*
X1056698Y-60698D01*
Y-68865D01*
G01X1067211Y-60990D02*
X1074198D01*
X1073543Y-58948D01*
X1072451Y-57782D01*
X1070923Y-57199D01*
X1069394Y-57490D01*
X1068084Y-58365D01*
X1067211Y-60407D01*
X1066774Y-62157D01*
Y-63907D01*
X1067211Y-65657D01*
X1068303Y-67407D01*
X1069613Y-68573D01*
X1071141Y-68865D01*
X1072669Y-68282D01*
X1074198Y-66532D01*
G01X1084929Y-68865D02*
Y-57199D01*
G01Y-59532D02*
X1086021Y-58365D01*
X1087113Y-57490D01*
X1088641Y-57199D01*
X1089732Y-57490D01*
X1091043Y-58365D01*
G01X1131686Y-113865D02*
Y-96365D01*
X1129066Y-99865D01*
G01Y-113865D02*
X1134306D01*
G01X1149186D02*
Y-96365D01*
X1146566Y-99865D01*
G01Y-113865D02*
X1151806D01*
G01X1162756Y-114448D02*
X1170616Y-96365D01*
G01X1184186Y-113865D02*
Y-96365D01*
X1181566Y-99865D01*
G01Y-113865D02*
X1186806D01*
G01X1196883Y-110365D02*
X1198192Y-112407D01*
X1199939Y-113573D01*
X1201904Y-113865D01*
X1203651Y-113573D01*
X1205398Y-112115D01*
X1206489Y-110365D01*
X1206708Y-108615D01*
X1206271Y-106574D01*
X1204743Y-105115D01*
X1203214Y-104532D01*
X1201249D01*
G01X1203214D02*
X1204524Y-103657D01*
X1205616Y-102199D01*
X1206053Y-100449D01*
X1205616Y-98698D01*
X1204524Y-97240D01*
X1202559Y-96365D01*
X1200594Y-96657D01*
X1198629Y-97824D01*
G01X1215256Y-114448D02*
X1223116Y-96365D01*
G01X1232538Y-99282D02*
X1233848Y-97532D01*
X1235376Y-96657D01*
X1237123Y-96365D01*
X1239306Y-96948D01*
X1240834Y-98407D01*
X1241271Y-100156D01*
X1241053Y-101907D01*
X1240179Y-103365D01*
X1235813Y-106282D01*
X1233848Y-108323D01*
X1232538Y-111241D01*
X1232101Y-113865D01*
X1241271D01*
G01X1254186Y-96365D02*
X1252439Y-96948D01*
X1251129Y-98407D01*
X1250256Y-100156D01*
X1249601Y-102490D01*
X1249383Y-105115D01*
X1249601Y-107740D01*
X1250256Y-110074D01*
X1251129Y-111824D01*
X1252439Y-113282D01*
X1254186Y-113865D01*
X1255932Y-113282D01*
X1257243Y-111824D01*
X1258116Y-110074D01*
X1258771Y-107740D01*
X1258989Y-105115D01*
X1258771Y-102490D01*
X1258116Y-100156D01*
X1257243Y-98407D01*
X1255932Y-96948D01*
X1254186Y-96365D01*
G01X1271686Y-113865D02*
Y-96365D01*
X1269066Y-99865D01*
G01Y-113865D02*
X1274306D01*
G01X1291806D02*
Y-96365D01*
X1283727Y-108907D01*
X1294645D01*
G01X1179383Y-68865D02*
Y-51365D01*
X1183749D01*
X1185496Y-52240D01*
X1186806Y-53407D01*
X1187898Y-55156D01*
X1188771Y-57199D01*
X1188989Y-60115D01*
X1188771Y-63032D01*
X1187898Y-65074D01*
X1186806Y-66824D01*
X1185496Y-67990D01*
X1183749Y-68865D01*
X1179383D01*
G01X1205616D02*
Y-57199D01*
G01Y-59240D02*
X1204743Y-58074D01*
X1203432Y-57490D01*
X1201904Y-57199D01*
X1200376Y-57782D01*
X1199066Y-58948D01*
X1198192Y-60698D01*
X1197756Y-63032D01*
X1198192Y-65365D01*
X1199066Y-67115D01*
X1200376Y-68282D01*
X1201904Y-68865D01*
X1203432Y-68573D01*
X1204743Y-67699D01*
X1205616Y-66532D01*
G01X1219186Y-51365D02*
Y-68865D01*
G01X1216129Y-57199D02*
X1222243D01*
G01X1233411Y-60990D02*
X1240398D01*
X1239743Y-58948D01*
X1238651Y-57782D01*
X1237123Y-57199D01*
X1235594Y-57490D01*
X1234284Y-58365D01*
X1233411Y-60407D01*
X1232974Y-62157D01*
Y-63907D01*
X1233411Y-65657D01*
X1234503Y-67407D01*
X1235813Y-68573D01*
X1237341Y-68865D01*
X1238869Y-68282D01*
X1240398Y-66532D01*
M02*
